FILE_TYPE = MACRO_DRAWING;
SET COLOR_WIRE YELLOW;
SET COLOR_PROP ORANGE;
SET COLOR_DOT WHITE;
SET COLOR_ARC YELLOW;
SET COLOR_BODY GREEN;
SET COLOR_NOTE PURPLE;
SET PROP_DISPLAY VALUE;
SET PAGE_NUMBER P236;
FORCEADD OFFPAGE..1
(-4700 12600);
PAINT AQUA (-4700 12600);
FORCEPROP 2 LAST $XR3 238 
J 0
(-5312 12600);
DISPLAY 0.638298 (-5312 12600);
PAINT MONO (-5312 12600);
FORCEPROP 2 LAST $XR2 157 
J 0
(-5192 12600);
DISPLAY 0.638298 (-5192 12600);
PAINT MONO (-5192 12600);
FORCEPROP 2 LAST $XR1 156 
J 0
(-5072 12600);
DISPLAY 0.638298 (-5072 12600);
PAINT MONO (-5072 12600);
FORCEPROP 2 LAST $XR0 158 
J 0
(-4952 12600);
DISPLAY 0.638298 (-4952 12600);
PAINT MONO (-4952 12600);
FORCEPROP 1 LAST OFFPAGE TRUE
J 0
(-4375 12475);
DISPLAY 0.872340 (-4375 12475);
PAINT AQUA (-4375 12475);
DISPLAY INVISIBLE (-4375 12475);
FORCEPROP 1 LAST COMMENT_BODY TRUE
J 0
(-4575 12500);
DISPLAY 0.872340 (-4575 12500);
PAINT GREEN (-4575 12500);
DISPLAY INVISIBLE (-4575 12500);
FORCEPROP 2 LAST CDS_LIB standard
J 0
(-4700 12600);
DISPLAY INVISIBLE (-4700 12600);
FORCEPROP 2 LAST PATH I31
J 0
(-4950 12650);
DISPLAY 1.021277 (-4950 12650);
DISPLAY INVISIBLE (-4950 12650);
FORCEADD UNIVERSAL_GND..1
(-4275 11925);
FORCEPROP 3 LASTPIN (-4275 11975) SIG_NAME GND\g
J 0
(-4265 11985);
DISPLAY 0.659574 (-4265 11985);
PAINT MONO (-4265 11985);
DISPLAY INVISIBLE (-4265 11985);
FORCEPROP 2 LAST CDS_LIB logical_power
J 0
(-4275 11925);
DISPLAY INVISIBLE (-4275 11925);
FORCEPROP 1 LAST HDL_POWER GND
J 1
(-4250 11850);
DISPLAY 0.872340 (-4250 11850);
PAINT GREEN (-4250 11850);
DISPLAY INVISIBLE (-4250 11850);
FORCEPROP 1 LAST PATH I41
J 0
(-4200 11925);
DISPLAY 0.872340 (-4200 11925);
PAINT AQUA (-4200 11925);
DISPLAY INVISIBLE (-4200 11925);
FORCEADD Q_CAP..1
(-4275 12300);
FORCEPROP 1 LAST PART_NUMBER CH0396J0B04
J 0
(-4225 12150);
DISPLAY 0.574468 (-4225 12150);
PAINT WHITE (-4225 12150);
DISPLAY INVISIBLE (-4225 12150);
FORCEPROP 1 LAST VOLTAGE 50V
J 0
(-4225 12250);
DISPLAY 0.574468 (-4225 12250);
PAINT SKYBLUE (-4225 12250);
FORCEPROP 1 LAST VALUE 39PF
J 0
(-4225 12325);
DISPLAY 0.574468 (-4225 12325);
PAINT SKYBLUE (-4225 12325);
FORCEPROP 2 LAST ROOM NIC1_P3V3_BOM2
J 0
(-4225 12425);
DISPLAY 0.510638 (-4225 12425);
FORCEPROP 1 LAST MATERIAL EMPTY
J 0
(-4225 12275);
DISPLAY 0.574468 (-4225 12275);
PAINT RED (-4225 12275);
FORCEPROP 1 LAST PACK_TYPE C0402
J 0
(-4225 12200);
DISPLAY 0.574468 (-4225 12200);
PAINT SKYBLUE (-4225 12200);
FORCEPROP 1 LAST LOCATION PC2157
J 0
(-4225 12375);
DISPLAY 0.723404 (-4225 12375);
PAINT AQUA (-4225 12375);
FORCEPROP 1 LAST PATH I42
J 0
(-4225 12450);
DISPLAY 0.978723 (-4225 12450);
PAINT WHITE (-4225 12450);
DISPLAY INVISIBLE (-4225 12450);
FORCEPROP 2 LAST CDS_LIB pure_quanta
J 0
(-4275 12300);
DISPLAY INVISIBLE (-4275 12300);
FORCEPROP 1 LAST TOLERANCE 5%
J 0
(-4225 12250);
DISPLAY 0.723404 (-4225 12250);
PAINT SKYBLUE (-4225 12250);
DISPLAY INVISIBLE (-4225 12250);
FORCEPROP 0 LAST $SEC 1
J 0
(-4225 12425);
DISPLAY INVISIBLE (-4225 12425);
FORCEPROP 0 LAST CDS_SEC 1
J 0
(-4225 12425);
DISPLAY INVISIBLE (-4225 12425);
FORCEPROP 1 LASTPIN (-4275 12400) $PN 1
J 0
(-4265 12380);
DISPLAY 0.787234 (-4265 12380);
PAINT MONO (-4265 12380);
DISPLAY INVISIBLE (-4265 12380);
FORCEPROP 1 LASTPIN (-4275 12200) $PN 2
J 0
(-4265 12180);
DISPLAY 0.787234 (-4265 12180);
PAINT MONO (-4265 12180);
DISPLAY INVISIBLE (-4265 12180);
FORCEADD Q_RES..2
(-3825 12300);
FORCEPROP 1 LAST PART_NUMBER CS37152FB05
J 0
(-3800 12175);
DISPLAY 0.468085 (-3800 12175);
PAINT WHITE (-3800 12175);
DISPLAY INVISIBLE (-3800 12175);
FORCEPROP 1 LAST PACK_TYPE 0402LF
J 0
(-3800 12225);
DISPLAY 0.574468 (-3800 12225);
PAINT SKYBLUE (-3800 12225);
FORCEPROP 1 LAST TOLERANCE 1%
J 0
(-3800 12275);
DISPLAY 0.574468 (-3800 12275);
PAINT SKYBLUE (-3800 12275);
FORCEPROP 1 LAST VALUE 71.5K
J 0
(-3800 12325);
DISPLAY 0.574468 (-3800 12325);
PAINT SKYBLUE (-3800 12325);
FORCEPROP 2 LAST ROOM NIC1_P3V3_BOM2
J 0
(-3800 12425);
DISPLAY 0.510638 (-3800 12425);
FORCEPROP 1 LAST MATERIAL EMPTY
J 0
(-3800 12125);
DISPLAY 0.723404 (-3800 12125);
PAINT RED (-3800 12125);
FORCEPROP 1 LAST LOCATION PR3844
J 0
(-3800 12375);
DISPLAY 0.723404 (-3800 12375);
PAINT AQUA (-3800 12375);
FORCEPROP 1 LAST PATH I43
J 0
(-3775 12475);
DISPLAY 0.978723 (-3775 12475);
PAINT WHITE (-3775 12475);
DISPLAY INVISIBLE (-3775 12475);
FORCEPROP 1 LAST WATTAGE 1/16W
J 0
(-3800 12275);
DISPLAY 0.723404 (-3800 12275);
PAINT SKYBLUE (-3800 12275);
DISPLAY INVISIBLE (-3800 12275);
FORCEPROP 2 LAST CDS_LIB pure_quanta
J 0
(-3825 12300);
DISPLAY INVISIBLE (-3825 12300);
FORCEPROP 0 LAST $SEC 1
J 0
(-3800 12425);
DISPLAY INVISIBLE (-3800 12425);
FORCEPROP 0 LAST CDS_SEC 1
J 0
(-3800 12425);
DISPLAY INVISIBLE (-3800 12425);
FORCEPROP 1 LASTPIN (-3825 12400) $PN 1
J 0
(-3820 12362);
DISPLAY 0.787234 (-3820 12362);
PAINT MONO (-3820 12362);
DISPLAY INVISIBLE (-3820 12362);
FORCEPROP 1 LASTPIN (-3825 12200) $PN 2
J 0
(-3820 12210);
DISPLAY 0.787234 (-3820 12210);
PAINT MONO (-3820 12210);
DISPLAY INVISIBLE (-3820 12210);
FORCEADD UNIVERSAL_GND..1
(-3525 11925);
FORCEPROP 3 LASTPIN (-3525 11975) SIG_NAME GND\g
J 0
(-3515 11985);
DISPLAY 0.659574 (-3515 11985);
PAINT MONO (-3515 11985);
DISPLAY INVISIBLE (-3515 11985);
FORCEPROP 2 LAST CDS_LIB logical_power
J 0
(-3525 11925);
DISPLAY INVISIBLE (-3525 11925);
FORCEPROP 1 LAST HDL_POWER GND
J 1
(-3500 11850);
DISPLAY 0.872340 (-3500 11850);
PAINT GREEN (-3500 11850);
DISPLAY INVISIBLE (-3500 11850);
FORCEPROP 1 LAST PATH I44
J 0
(-3450 11925);
DISPLAY 0.872340 (-3450 11925);
PAINT AQUA (-3450 11925);
DISPLAY INVISIBLE (-3450 11925);
FORCEADD Q_RES..1
R 1
(-3525 12250);
FORCEPROP 1 LAST PART_NUMBER CS21332FB05
J 0
(-3450 12075);
DISPLAY 0.638298 (-3450 12075);
DISPLAY INVISIBLE (-3450 12075);
FORCEPROP 1 LAST VALUE 1.33K
J 0
(-3450 12225);
DISPLAY 0.638298 (-3450 12225);
FORCEPROP 2 LAST ROOM NIC1_P3V3_BOM2
J 0
(-3450 12325);
DISPLAY 0.510638 (-3450 12325);
FORCEPROP 1 LAST MATERIAL EMPTY
J 0
(-3450 12000);
DISPLAY 0.787234 (-3450 12000);
PAINT RED (-3450 12000);
FORCEPROP 1 LAST PACK_TYPE 0402LF
J 0
(-3450 12125);
DISPLAY 0.638298 (-3450 12125);
FORCEPROP 1 LAST TOLERANCE 1%
J 0
(-3450 12175);
DISPLAY 0.638298 (-3450 12175);
FORCEPROP 1 LAST LOCATION PR3846
J 0
(-3450 12275);
DISPLAY 0.808511 (-3450 12275);
FORCEPROP 1 LAST PATH I45
R 1
J 0
(-3675 12200);
DISPLAY 0.978723 (-3675 12200);
PAINT WHITE (-3675 12200);
DISPLAY INVISIBLE (-3675 12200);
FORCEPROP 1 LAST WATTAGE 1/16W
R 1
J 2
(-3375 12225);
DISPLAY 0.978723 (-3375 12225);
DISPLAY INVISIBLE (-3375 12225);
FORCEPROP 2 LAST CDS_LIB pure_quanta
R 1
J 0
(-3525 12250);
DISPLAY INVISIBLE (-3525 12250);
FORCEPROP 0 LAST $SEC 1
R 1
J 0
(-3500 12325);
DISPLAY INVISIBLE (-3500 12325);
FORCEPROP 0 LAST CDS_SEC 1
R 1
J 0
(-3500 12325);
DISPLAY INVISIBLE (-3500 12325);
FORCEPROP 1 LASTPIN (-3525 12150) $PN 1
R 1
J 0
(-3537 12162);
DISPLAY 0.787234 (-3537 12162);
PAINT MONO (-3537 12162);
DISPLAY INVISIBLE (-3537 12162);
FORCEPROP 1 LASTPIN (-3525 12350) $PN 2
R 1
J 0
(-3537 12312);
DISPLAY 0.787234 (-3537 12312);
PAINT MONO (-3537 12312);
DISPLAY INVISIBLE (-3537 12312);
FORCEADD Q_RES..1
(-3775 12600);
FORCEPROP 1 LAST PART_NUMBER CS00002JB13
J 0
(-3850 12550);
DISPLAY 0.510638 (-3850 12550);
DISPLAY INVISIBLE (-3850 12550);
FORCEPROP 1 LAST TOLERANCE 5%
J 0
(-3600 12600);
DISPLAY 0.510638 (-3600 12600);
FORCEPROP 1 LAST VALUE 0
J 2
(-3625 12600);
DISPLAY 0.510638 (-3625 12600);
FORCEPROP 1 LAST PACK_TYPE 0402LF
J 0
(-3525 12600);
DISPLAY 0.510638 (-3525 12600);
FORCEPROP 1 LAST WATTAGE 1/16W
J 2
(-3600 12525);
DISPLAY 0.510638 (-3600 12525);
FORCEPROP 1 LAST MATERIAL EMPTY
J 0
(-3850 12525);
DISPLAY 0.510638 (-3850 12525);
PAINT RED (-3850 12525);
FORCEPROP 2 LAST ROOM NIC1_P3V3_BOM2
J 0
(-4000 12650);
DISPLAY 0.638298 (-4000 12650);
FORCEPROP 1 LAST LOCATION R3845
J 0
(-4000 12600);
DISPLAY 0.787234 (-4000 12600);
FORCEPROP 1 LASTPIN (-3875 12600) $PN 1
J 0
(-3863 12612);
DISPLAY 0.787234 (-3863 12612);
PAINT MONO (-3863 12612);
FORCEPROP 1 LASTPIN (-3675 12600) $PN 2
J 0
(-3713 12612);
DISPLAY 0.787234 (-3713 12612);
PAINT MONO (-3713 12612);
FORCEPROP 1 LAST PATH I46
J 0
(-3825 12750);
DISPLAY 0.978723 (-3825 12750);
PAINT WHITE (-3825 12750);
DISPLAY INVISIBLE (-3825 12750);
FORCEPROP 2 LAST CDS_LIB pure_quanta
J 0
(-3775 12600);
DISPLAY INVISIBLE (-3775 12600);
FORCEPROP 0 LAST $SEC 1
J 0
(-4000 12650);
DISPLAY 0.680851 (-4000 12650);
PAINT MONO (-4000 12650);
DISPLAY INVISIBLE (-4000 12650);
FORCEPROP 0 LAST CDS_SEC 1
J 0
(-4000 12650);
DISPLAY 1.021277 (-4000 12650);
DISPLAY INVISIBLE (-4000 12650);
FORCEADD UNIVERSAL_GND..1
(-3550 12650);
FORCEPROP 3 LASTPIN (-3550 12700) SIG_NAME GND\g
J 0
(-3540 12710);
DISPLAY 0.659574 (-3540 12710);
PAINT MONO (-3540 12710);
DISPLAY INVISIBLE (-3540 12710);
FORCEPROP 1 LAST HDL_POWER GND
J 1
(-3525 12575);
DISPLAY 0.872340 (-3525 12575);
PAINT GREEN (-3525 12575);
DISPLAY INVISIBLE (-3525 12575);
FORCEPROP 2 LAST CDS_LIB logical_power
J 0
(-3550 12650);
DISPLAY INVISIBLE (-3550 12650);
FORCEPROP 1 LAST PATH I47
J 0
(-3475 12650);
DISPLAY 0.872340 (-3475 12650);
PAINT AQUA (-3475 12650);
DISPLAY INVISIBLE (-3475 12650);
FORCEADD UNIVERSAL_GND..1
(-2975 11925);
FORCEPROP 3 LASTPIN (-2975 11975) SIG_NAME GND\g
J 0
(-2965 11985);
DISPLAY 0.659574 (-2965 11985);
PAINT MONO (-2965 11985);
DISPLAY INVISIBLE (-2965 11985);
FORCEPROP 2 LAST CDS_LIB logical_power
J 0
(-2975 11925);
DISPLAY INVISIBLE (-2975 11925);
FORCEPROP 1 LAST HDL_POWER GND
J 1
(-2950 11850);
DISPLAY 0.872340 (-2950 11850);
PAINT GREEN (-2950 11850);
DISPLAY INVISIBLE (-2950 11850);
FORCEPROP 1 LAST PATH I48
J 0
(-2900 11925);
DISPLAY 0.872340 (-2900 11925);
PAINT AQUA (-2900 11925);
DISPLAY INVISIBLE (-2900 11925);
FORCEADD Q_CAP..1
(-2975 12225);
FORCEPROP 1 LAST PART_NUMBER CH3683K1B09
J 0
(-2925 12100);
DISPLAY 0.574468 (-2925 12100);
PAINT WHITE (-2925 12100);
DISPLAY INVISIBLE (-2925 12100);
FORCEPROP 1 LAST MATERIAL EMPTY
J 0
(-2925 12250);
DISPLAY 0.574468 (-2925 12250);
PAINT RED (-2925 12250);
FORCEPROP 1 LAST VALUE 0.068UF
J 0
(-2925 12300);
DISPLAY 0.574468 (-2925 12300);
PAINT SKYBLUE (-2925 12300);
FORCEPROP 1 LAST VOLTAGE 16V
J 0
(-2925 12200);
DISPLAY 0.574468 (-2925 12200);
PAINT SKYBLUE (-2925 12200);
FORCEPROP 1 LAST PACK_TYPE 0402
J 0
(-2925 12150);
DISPLAY 0.574468 (-2925 12150);
PAINT SKYBLUE (-2925 12150);
FORCEPROP 2 LAST ROOM NIC1_P3V3_BOM2
J 0
(-2925 12050);
DISPLAY 0.638298 (-2925 12050);
FORCEPROP 1 LAST LOCATION PC2161
J 0
(-2925 12325);
DISPLAY 0.723404 (-2925 12325);
PAINT AQUA (-2925 12325);
FORCEPROP 1 LAST PATH I49
J 0
(-2925 12375);
DISPLAY 0.978723 (-2925 12375);
PAINT WHITE (-2925 12375);
DISPLAY INVISIBLE (-2925 12375);
FORCEPROP 1 LAST TOLERANCE 10%
J 0
(-2925 12175);
DISPLAY 0.723404 (-2925 12175);
PAINT SKYBLUE (-2925 12175);
DISPLAY INVISIBLE (-2925 12175);
FORCEPROP 2 LAST CDS_LIB pure_quanta
J 0
(-2975 12225);
DISPLAY INVISIBLE (-2975 12225);
FORCEPROP 0 LAST $SEC 1
J 0
(-2925 12375);
DISPLAY INVISIBLE (-2925 12375);
FORCEPROP 0 LAST CDS_SEC 1
J 0
(-2925 12375);
DISPLAY INVISIBLE (-2925 12375);
FORCEPROP 1 LASTPIN (-2975 12325) $PN 1
J 0
(-2965 12305);
DISPLAY 0.787234 (-2965 12305);
PAINT MONO (-2965 12305);
DISPLAY INVISIBLE (-2965 12305);
FORCEPROP 1 LASTPIN (-2975 12125) $PN 2
J 0
(-2965 12105);
DISPLAY 0.787234 (-2965 12105);
PAINT MONO (-2965 12105);
DISPLAY INVISIBLE (-2965 12105);
FORCEADD MP5016GQHLZ..1
(-2325 12550);
FORCEPROP 1 LAST PART_NUMBER AL005016007
J 0
(-2570 12884);
DISPLAY 0.723404 (-2570 12884);
PAINT GREEN (-2570 12884);
DISPLAY INVISIBLE (-2570 12884);
FORCEPROP 2 LAST PART_TYPE SMLF
J 0
(-2550 13125);
DISPLAY 0.680851 (-2550 13125);
FORCEPROP 1 LAST MATERIAL EMPTY
J 0
(-2570 12757);
DISPLAY 0.723404 (-2570 12757);
PAINT RED (-2570 12757);
FORCEPROP 2 LAST VALUE MP5016GQH-L-Z
J 0
(-2550 13075);
DISPLAY 0.680851 (-2550 13075);
FORCEPROP 2 LAST ROOM NIC1_P3V3_BOM2
J 0
(-2550 13175);
DISPLAY 0.808511 (-2550 13175);
FORCEPROP 1 LAST LOCATION PU205
J 0
(-2570 13031);
DISPLAY 0.723404 (-2570 13031);
PAINT GREEN (-2570 13031);
FORCEPROP 0 LASTPIN (-2725 12400) $PN 10
J 2
(-2735 12410);
DISPLAY 0.808511 (-2735 12410);
FORCEPROP 0 LASTPIN (-2725 12600) $PN 9
J 2
(-2735 12610);
DISPLAY 0.808511 (-2735 12610);
FORCEPROP 0 LASTPIN (-1925 12500) $PN 8
J 0
(-1915 12510);
DISPLAY 0.808511 (-1915 12510);
FORCEPROP 0 LASTPIN (-1925 12400) $PN 3
J 0
(-1915 12410);
DISPLAY 0.808511 (-1915 12410);
FORCEPROP 0 LASTPIN (-2725 12450) $PN 4
J 2
(-2735 12460);
DISPLAY 0.808511 (-2735 12460);
FORCEPROP 0 LASTPIN (-2725 12500) $PN 5
J 2
(-2735 12510);
DISPLAY 0.808511 (-2735 12510);
FORCEPROP 0 LASTPIN (-1925 12700) $PN 6_7
J 0
(-1915 12710);
DISPLAY 0.808511 (-1915 12710);
FORCEPROP 0 LASTPIN (-2725 12700) $PN 1_2
J 2
(-2735 12710);
DISPLAY 0.808511 (-2735 12710);
FORCEPROP 2 LAST CDS_LIB pure_quanta
J 0
(-2325 12550);
DISPLAY INVISIBLE (-2325 12550);
FORCEPROP 1 LAST CDS_LMAN_SYM_OUTLINE -250,200,250,-200
J 0
(-2325 12550);
DISPLAY 0.468085 (-2325 12550);
PAINT GREEN (-2325 12550);
DISPLAY INVISIBLE (-2325 12550);
FORCEPROP 1 LAST NEEDS_NO_SIZE TRUE
J 0
(-2325 12550);
DISPLAY 0.723404 (-2325 12550);
PAINT GREEN (-2325 12550);
DISPLAY INVISIBLE (-2325 12550);
FORCEPROP 1 LAST PATH I50
J 0
(-2325 12550);
DISPLAY 0.723404 (-2325 12550);
PAINT GREEN (-2325 12550);
DISPLAY INVISIBLE (-2325 12550);
FORCEPROP 0 LAST $SEC 1
J 0
(-2550 13175);
DISPLAY INVISIBLE (-2550 13175);
FORCEPROP 0 LAST CDS_SEC 1
J 0
(-2550 13175);
DISPLAY INVISIBLE (-2550 13175);
FORCEADD UNIVERSAL_GND..1
(-1475 11800);
FORCEPROP 3 LASTPIN (-1475 11850) SIG_NAME GND\g
J 0
(-1465 11860);
DISPLAY 0.659574 (-1465 11860);
PAINT MONO (-1465 11860);
DISPLAY INVISIBLE (-1465 11860);
FORCEPROP 2 LAST CDS_LIB logical_power
J 0
(-1475 11800);
DISPLAY INVISIBLE (-1475 11800);
FORCEPROP 1 LAST HDL_POWER GND
J 1
(-1450 11725);
DISPLAY 0.872340 (-1450 11725);
PAINT GREEN (-1450 11725);
DISPLAY INVISIBLE (-1450 11725);
FORCEPROP 1 LAST PATH I51
J 0
(-1400 11800);
DISPLAY 0.872340 (-1400 11800);
PAINT AQUA (-1400 11800);
DISPLAY INVISIBLE (-1400 11800);
FORCEADD Q_CAP..1
(-1475 12150);
FORCEPROP 1 LAST PART_NUMBER CH11006JB18
J 0
(-1425 12000);
DISPLAY 0.787234 (-1425 12000);
DISPLAY INVISIBLE (-1425 12000);
FORCEPROP 1 LAST VOLTAGE 50V
J 0
(-1425 12150);
DISPLAY 0.787234 (-1425 12150);
FORCEPROP 1 LAST VALUE 100PF
J 0
(-1425 12200);
DISPLAY 0.787234 (-1425 12200);
FORCEPROP 1 LAST PACK_TYPE 0402
J 0
(-1425 11950);
DISPLAY 0.787234 (-1425 11950);
FORCEPROP 1 LAST MATERIAL EMPTY
J 0
(-1425 12050);
DISPLAY 0.787234 (-1425 12050);
PAINT RED (-1425 12050);
FORCEPROP 1 LAST TOLERANCE 5%
J 0
(-1425 12100);
DISPLAY 0.787234 (-1425 12100);
FORCEPROP 2 LAST ROOM NIC1_P3V3_BOM2
J 0
(-1425 12300);
DISPLAY 0.638298 (-1425 12300);
FORCEPROP 1 LAST LOCATION PC2162
J 0
(-1425 12250);
DISPLAY 0.787234 (-1425 12250);
FORCEPROP 1 LAST PATH I52
J 0
(-1425 12300);
DISPLAY 0.978723 (-1425 12300);
PAINT WHITE (-1425 12300);
DISPLAY INVISIBLE (-1425 12300);
FORCEPROP 2 LAST CDS_LIB pure_quanta
J 0
(-1475 12150);
DISPLAY INVISIBLE (-1475 12150);
FORCEPROP 0 LAST $SEC 1
J 0
(-1425 12300);
DISPLAY INVISIBLE (-1425 12300);
FORCEPROP 0 LAST CDS_SEC 1
J 0
(-1425 12300);
DISPLAY INVISIBLE (-1425 12300);
FORCEPROP 1 LASTPIN (-1475 12250) $PN 1
J 0
(-1465 12230);
DISPLAY 0.787234 (-1465 12230);
PAINT MONO (-1465 12230);
DISPLAY INVISIBLE (-1465 12230);
FORCEPROP 1 LASTPIN (-1475 12050) $PN 2
J 0
(-1465 12030);
DISPLAY 0.787234 (-1465 12030);
PAINT MONO (-1465 12030);
DISPLAY INVISIBLE (-1465 12030);
FORCEADD UNIVERSAL_GND..1
(-875 12025);
FORCEPROP 3 LASTPIN (-875 12075) SIG_NAME GND\g
J 0
(-865 12085);
DISPLAY 0.659574 (-865 12085);
PAINT MONO (-865 12085);
DISPLAY INVISIBLE (-865 12085);
FORCEPROP 2 LAST CDS_LIB logical_power
J 0
(-875 12025);
DISPLAY INVISIBLE (-875 12025);
FORCEPROP 1 LAST HDL_POWER GND
J 1
(-850 11950);
DISPLAY 0.872340 (-850 11950);
PAINT GREEN (-850 11950);
DISPLAY INVISIBLE (-850 11950);
FORCEPROP 1 LAST PATH I53
J 0
(-800 12025);
DISPLAY 0.872340 (-800 12025);
PAINT AQUA (-800 12025);
DISPLAY INVISIBLE (-800 12025);
FORCEADD Q_CAP..1
(-875 12375);
FORCEPROP 1 LAST PART_NUMBER CH6103KEA01
J 0
(-825 12200);
DISPLAY 0.574468 (-825 12200);
PAINT WHITE (-825 12200);
DISPLAY INVISIBLE (-825 12200);
FORCEPROP 1 LAST VOLTAGE 16V
J 0
(-825 12300);
DISPLAY 0.574468 (-825 12300);
PAINT SKYBLUE (-825 12300);
FORCEPROP 1 LAST PACK_TYPE C0805
J 0
(-825 12250);
DISPLAY 0.574468 (-825 12250);
PAINT SKYBLUE (-825 12250);
FORCEPROP 1 LAST MATERIAL EMPTY
J 0
(-825 12350);
DISPLAY 0.574468 (-825 12350);
PAINT RED (-825 12350);
FORCEPROP 2 LAST ROOM NIC1_P3V3_BOM2
J 0
(-825 12500);
DISPLAY 0.638298 (-825 12500);
FORCEPROP 1 LAST VALUE 10UF
J 0
(-825 12400);
DISPLAY 0.574468 (-825 12400);
PAINT SKYBLUE (-825 12400);
FORCEPROP 1 LAST LOCATION PC2163
J 0
(-825 12450);
DISPLAY 0.723404 (-825 12450);
PAINT AQUA (-825 12450);
FORCEPROP 1 LAST PATH I54
J 0
(-825 12525);
DISPLAY 0.978723 (-825 12525);
PAINT WHITE (-825 12525);
DISPLAY INVISIBLE (-825 12525);
FORCEPROP 1 LAST TOLERANCE 10%
J 0
(-825 12325);
DISPLAY 0.723404 (-825 12325);
PAINT SKYBLUE (-825 12325);
DISPLAY INVISIBLE (-825 12325);
FORCEPROP 2 LAST CDS_LIB pure_quanta
J 0
(-875 12375);
DISPLAY INVISIBLE (-875 12375);
FORCEPROP 0 LAST $SEC 1
J 0
(-825 12500);
DISPLAY INVISIBLE (-825 12500);
FORCEPROP 0 LAST CDS_SEC 1
J 0
(-825 12500);
DISPLAY INVISIBLE (-825 12500);
FORCEPROP 1 LASTPIN (-875 12475) $PN 1
J 0
(-865 12455);
DISPLAY 0.787234 (-865 12455);
PAINT MONO (-865 12455);
DISPLAY INVISIBLE (-865 12455);
FORCEPROP 1 LASTPIN (-875 12275) $PN 2
J 0
(-865 12255);
DISPLAY 0.787234 (-865 12255);
PAINT MONO (-865 12255);
DISPLAY INVISIBLE (-865 12255);
FORCEADD Q_CAP..1
(-3550 12875);
FORCEPROP 1 LAST PART_NUMBER CH5104KEB02
J 0
(-3500 12725);
DISPLAY 0.510638 (-3500 12725);
DISPLAY INVISIBLE (-3500 12725);
FORCEPROP 2 LAST ROOM NIC1_P3V3_BOM2
J 0
(-3500 13025);
DISPLAY 0.638298 (-3500 13025);
FORCEPROP 1 LAST PACK_TYPE C0402
J 0
(-3500 12775);
DISPLAY 0.510638 (-3500 12775);
FORCEPROP 1 LAST VOLTAGE 25V
J 0
(-3500 12825);
DISPLAY 0.510638 (-3500 12825);
FORCEPROP 1 LAST MATERIAL EMPTY
J 0
(-3500 12875);
DISPLAY 0.510638 (-3500 12875);
PAINT RED (-3500 12875);
FORCEPROP 1 LAST VALUE 1UF
J 0
(-3500 12925);
DISPLAY 0.510638 (-3500 12925);
FORCEPROP 1 LAST LOCATION PC2159
J 0
(-3500 12975);
DISPLAY 0.638298 (-3500 12975);
FORCEPROP 2 LAST CDS_LIB pure_quanta
J 0
(-3550 12875);
DISPLAY INVISIBLE (-3550 12875);
FORCEPROP 1 LAST TOLERANCE 10%
J 0
(-3500 12825);
DISPLAY 0.638298 (-3500 12825);
DISPLAY INVISIBLE (-3500 12825);
FORCEPROP 1 LAST PATH I55
J 0
(-3500 13025);
DISPLAY 0.978723 (-3500 13025);
PAINT WHITE (-3500 13025);
DISPLAY INVISIBLE (-3500 13025);
FORCEPROP 0 LAST $SEC 1
J 0
(-3500 13025);
DISPLAY INVISIBLE (-3500 13025);
FORCEPROP 0 LAST CDS_SEC 1
J 0
(-3500 13025);
DISPLAY INVISIBLE (-3500 13025);
FORCEPROP 1 LASTPIN (-3550 12975) $PN 1
J 0
(-3540 12955);
DISPLAY 0.787234 (-3540 12955);
PAINT MONO (-3540 12955);
DISPLAY INVISIBLE (-3540 12955);
FORCEPROP 1 LASTPIN (-3550 12775) $PN 2
J 0
(-3540 12755);
DISPLAY 0.787234 (-3540 12755);
PAINT MONO (-3540 12755);
DISPLAY INVISIBLE (-3540 12755);
FORCEADD UNIVERSAL_POWER..1
R 2
(-3550 13200);
FORCEPROP 3 LASTPIN (-3550 13150) SIG_NAME P3V3_AUX\g
J 0
(-3540 13160);
DISPLAY 0.659574 (-3540 13160);
PAINT MONO (-3540 13160);
DISPLAY INVISIBLE (-3540 13160);
FORCEPROP 1 LAST HDL_POWER P3V3_AUX
J 1
(-3550 13250);
DISPLAY 0.723404 (-3550 13250);
PAINT GREEN (-3550 13250);
FORCEPROP 2 LAST CDS_LIB logical_power
J 0
(-3550 13200);
DISPLAY INVISIBLE (-3550 13200);
FORCEPROP 1 LAST PATH I56
J 2
(-3600 13225);
DISPLAY 0.872340 (-3600 13225);
PAINT AQUA (-3600 13225);
DISPLAY INVISIBLE (-3600 13225);
FORCEADD UNIVERSAL_POWER..1
R 2
(-875 13025);
FORCEPROP 3 LASTPIN (-875 12975) SIG_NAME P3V3_OCP_SFF_R\g
J 0
(-865 12985);
DISPLAY 0.659574 (-865 12985);
PAINT MONO (-865 12985);
DISPLAY INVISIBLE (-865 12985);
FORCEPROP 1 LAST HDL_POWER P3V3_OCP_SFF_R
J 1
(-875 13075);
DISPLAY 0.723404 (-875 13075);
PAINT GREEN (-875 13075);
FORCEPROP 2 LAST CDS_LIB logical_power
J 0
(-875 13025);
DISPLAY INVISIBLE (-875 13025);
FORCEPROP 1 LAST PATH I57
J 2
(-925 13050);
DISPLAY 0.872340 (-925 13050);
PAINT AQUA (-925 13050);
DISPLAY INVISIBLE (-925 13050);
FORCEADD OFFPAGE..1
(-8575 9650);
PAINT AQUA (-8575 9650);
FORCEPROP 2 LAST $XR3 238 
J 0
(-9217 9650);
DISPLAY 0.638298 (-9217 9650);
PAINT MONO (-9217 9650);
FORCEPROP 2 LAST $XR2 157 
J 0
(-9097 9650);
DISPLAY 0.638298 (-9097 9650);
PAINT MONO (-9097 9650);
FORCEPROP 2 LAST $XR1 156 
J 0
(-8977 9650);
DISPLAY 0.638298 (-8977 9650);
PAINT MONO (-8977 9650);
FORCEPROP 2 LAST $XR0 158 
J 0
(-8857 9650);
DISPLAY 0.638298 (-8857 9650);
PAINT MONO (-8857 9650);
FORCEPROP 1 LAST COMMENT_BODY TRUE
J 0
(-8450 9550);
DISPLAY 0.872340 (-8450 9550);
PAINT GREEN (-8450 9550);
DISPLAY INVISIBLE (-8450 9550);
FORCEPROP 1 LAST OFFPAGE TRUE
J 0
(-8250 9525);
DISPLAY 0.872340 (-8250 9525);
PAINT AQUA (-8250 9525);
DISPLAY INVISIBLE (-8250 9525);
FORCEPROP 2 LAST CDS_LIB standard
J 0
(-8575 9650);
DISPLAY INVISIBLE (-8575 9650);
FORCEPROP 2 LAST PATH I58
J 0
(-9050 9700);
DISPLAY 1.021277 (-9050 9700);
DISPLAY INVISIBLE (-9050 9700);
FORCEADD GND..1
(-8050 8850);
FORCEPROP 3 LASTPIN (-8050 8900) SIG_NAME GND\g
J 0
(-8040 8910);
DISPLAY 0.659574 (-8040 8910);
PAINT MONO (-8040 8910);
DISPLAY INVISIBLE (-8040 8910);
FORCEPROP 1 LAST HDL_POWER GND
J 0
(-8050 9000);
DISPLAY 0.872340 (-8050 9000);
PAINT GREEN (-8050 9000);
DISPLAY INVISIBLE (-8050 9000);
FORCEPROP 1 LAST SIZE 1B
J 0
(-7975 8800);
DISPLAY 0.872340 (-7975 8800);
PAINT GREEN (-7975 8800);
DISPLAY INVISIBLE (-7975 8800);
FORCEPROP 2 LAST CDS_LIB logical_power
J 0
(-8050 8850);
DISPLAY INVISIBLE (-8050 8850);
FORCEPROP 1 LAST PATH I59
J 0
(-7975 8850);
DISPLAY 0.872340 (-7975 8850);
PAINT AQUA (-7975 8850);
DISPLAY INVISIBLE (-7975 8850);
FORCEADD Q_CAP..1
(-8050 9200);
FORCEPROP 1 LAST PART_NUMBER CH4223K1B00
J 0
(-8000 9050);
DISPLAY 0.510638 (-8000 9050);
DISPLAY INVISIBLE (-8000 9050);
FORCEPROP 1 LAST VALUE 0.22UF
J 0
(-8000 9250);
DISPLAY 0.510638 (-8000 9250);
FORCEPROP 1 LAST MATERIAL X7R
J 0
(-8005 9158);
DISPLAY 0.510638 (-8005 9158);
FORCEPROP 1 LAST PACK_TYPE 0402
J 0
(-8005 9108);
DISPLAY 0.510638 (-8005 9108);
FORCEPROP 2 LAST ROOM NIC1_P12V_MPS_MAM_BOM3
J 0
(-8000 9000);
DISPLAY 0.404255 (-8000 9000);
FORCEPROP 1 LAST VOLTAGE 16V
J 0
(-8000 9200);
DISPLAY 0.510638 (-8000 9200);
FORCEPROP 1 LAST LOCATION PC2153
J 0
(-8000 9300);
DISPLAY 0.510638 (-8000 9300);
FORCEPROP 2 LAST ROOM1 NIC1_P12V_MPS_TIC_BOM4
J 0
(-8000 9400);
DISPLAY 1.021277 (-8000 9400);
DISPLAY INVISIBLE (-8000 9400);
FORCEPROP 2 LAST CDS_LIB pure_quanta
J 0
(-8050 9200);
DISPLAY INVISIBLE (-8050 9200);
FORCEPROP 1 LAST TOLERANCE 10%
J 0
(-8000 9150);
DISPLAY 0.638298 (-8000 9150);
DISPLAY INVISIBLE (-8000 9150);
FORCEPROP 1 LAST PATH I60
J 0
(-8000 9350);
DISPLAY 0.978723 (-8000 9350);
PAINT WHITE (-8000 9350);
DISPLAY INVISIBLE (-8000 9350);
FORCEPROP 0 LAST $SEC 1
J 0
(-8000 9350);
DISPLAY INVISIBLE (-8000 9350);
FORCEPROP 0 LAST CDS_SEC 1
J 0
(-8000 9350);
DISPLAY INVISIBLE (-8000 9350);
FORCEPROP 1 LASTPIN (-8050 9300) $PN 1
J 0
(-8040 9280);
DISPLAY 0.787234 (-8040 9280);
PAINT MONO (-8040 9280);
DISPLAY INVISIBLE (-8040 9280);
FORCEPROP 1 LASTPIN (-8050 9100) $PN 2
J 0
(-8040 9080);
DISPLAY 0.787234 (-8040 9080);
PAINT MONO (-8040 9080);
DISPLAY INVISIBLE (-8040 9080);
FORCEADD GND..1
(-7625 8775);
FORCEPROP 3 LASTPIN (-7625 8825) SIG_NAME GND\g
J 0
(-7615 8835);
DISPLAY 0.659574 (-7615 8835);
PAINT MONO (-7615 8835);
DISPLAY INVISIBLE (-7615 8835);
FORCEPROP 1 LAST HDL_POWER GND
J 0
(-7625 8925);
DISPLAY 0.872340 (-7625 8925);
PAINT GREEN (-7625 8925);
DISPLAY INVISIBLE (-7625 8925);
FORCEPROP 1 LAST SIZE 1B
J 0
(-7550 8725);
DISPLAY 0.872340 (-7550 8725);
PAINT GREEN (-7550 8725);
DISPLAY INVISIBLE (-7550 8725);
FORCEPROP 2 LAST CDS_LIB logical_power
J 0
(-7625 8775);
DISPLAY INVISIBLE (-7625 8775);
FORCEPROP 1 LAST PATH I61
J 0
(-7550 8775);
DISPLAY 0.872340 (-7550 8775);
PAINT AQUA (-7550 8775);
DISPLAY INVISIBLE (-7550 8775);
FORCEADD Q_RES..2
(-7625 9075);
FORCEPROP 1 LAST PART_NUMBER CS31432FB02
J 0
(-7585 8950);
DISPLAY 0.510638 (-7585 8950);
DISPLAY INVISIBLE (-7585 8950);
FORCEPROP 1 LAST VALUE 14.3K
J 0
(-7580 9150);
DISPLAY 0.510638 (-7580 9150);
FORCEPROP 1 LAST TOLERANCE 1%
J 0
(-7580 9100);
DISPLAY 0.510638 (-7580 9100);
FORCEPROP 1 LAST WATTAGE 1/16W
J 0
(-7585 9050);
DISPLAY 0.510638 (-7585 9050);
FORCEPROP 1 LAST MATERIAL CHIP
J 0
(-7585 9000);
DISPLAY 0.510638 (-7585 9000);
FORCEPROP 2 LAST ROOM NIC1_P12V_MPS_MAM_BOM3
J 0
(-7600 8850);
DISPLAY 0.510638 (-7600 8850);
FORCEPROP 1 LAST PACK_TYPE 0402LF
J 0
(-7585 8900);
DISPLAY 0.510638 (-7585 8900);
FORCEPROP 1 LAST LOCATION PR3835
J 0
(-7575 9200);
DISPLAY 0.510638 (-7575 9200);
FORCEPROP 1 LASTPIN (-7625 9175) $PN 1
J 0
(-7620 9137);
DISPLAY 0.510638 (-7620 9137);
PAINT MONO (-7620 9137);
FORCEPROP 1 LASTPIN (-7625 8975) $PN 2
J 0
(-7620 8985);
DISPLAY 0.510638 (-7620 8985);
PAINT MONO (-7620 8985);
FORCEPROP 2 LAST ROOM1 NIC1_P12V_MPS_TIC_BOM4
J 0
(-7575 9300);
DISPLAY 1.021277 (-7575 9300);
DISPLAY INVISIBLE (-7575 9300);
FORCEPROP 2 LAST CDS_LIB pure_quanta
J 0
(-7625 9075);
DISPLAY INVISIBLE (-7625 9075);
FORCEPROP 1 LAST PATH I62
J 0
(-7575 9250);
DISPLAY 0.978723 (-7575 9250);
PAINT WHITE (-7575 9250);
DISPLAY INVISIBLE (-7575 9250);
FORCEPROP 0 LAST $SEC 1
J 0
(-7575 9225);
DISPLAY 0.680851 (-7575 9225);
PAINT MONO (-7575 9225);
DISPLAY INVISIBLE (-7575 9225);
FORCEPROP 0 LAST CDS_SEC 1
J 0
(-7575 9200);
DISPLAY INVISIBLE (-7575 9200);
FORCEADD Q_CAP..1
(-7225 8975);
FORCEPROP 1 LAST PART_NUMBER CH3474K1B04
J 0
(-7183 8824);
DISPLAY 0.510638 (-7183 8824);
DISPLAY INVISIBLE (-7183 8824);
FORCEPROP 2 LAST ROOM NIC1_P12V_MPS_MAM_BOM3
J 0
(-7175 9125);
DISPLAY 0.510638 (-7175 9125);
FORCEPROP 1 LAST VALUE 0.047UF
J 0
(-7175 9025);
DISPLAY 0.510638 (-7175 9025);
FORCEPROP 1 LAST VOLTAGE 25V
J 0
(-7183 8924);
DISPLAY 0.510638 (-7183 8924);
FORCEPROP 1 LAST PACK_TYPE C0402
J 0
(-7183 8874);
DISPLAY 0.510638 (-7183 8874);
FORCEPROP 1 LAST MATERIAL X7R
J 0
(-7183 8974);
DISPLAY 0.510638 (-7183 8974);
FORCEPROP 1 LAST LOCATION PC2155
J 0
(-7175 9075);
DISPLAY 0.510638 (-7175 9075);
FORCEPROP 2 LAST ROOM1 NIC1_P12V_MPS_TIC_BOM4
J 0
(-7175 9175);
DISPLAY 1.021277 (-7175 9175);
DISPLAY INVISIBLE (-7175 9175);
FORCEPROP 2 LAST CDS_LIB pure_quanta
J 0
(-7225 8975);
DISPLAY INVISIBLE (-7225 8975);
FORCEPROP 1 LAST TOLERANCE 10%
J 0
(-7175 8925);
DISPLAY 0.638298 (-7175 8925);
DISPLAY INVISIBLE (-7175 8925);
FORCEPROP 1 LAST PATH I63
J 0
(-7175 9125);
DISPLAY 0.978723 (-7175 9125);
PAINT WHITE (-7175 9125);
DISPLAY INVISIBLE (-7175 9125);
FORCEPROP 0 LAST $SEC 1
J 0
(-7175 9125);
DISPLAY INVISIBLE (-7175 9125);
FORCEPROP 0 LAST CDS_SEC 1
J 0
(-7175 9125);
DISPLAY INVISIBLE (-7175 9125);
FORCEPROP 1 LASTPIN (-7225 9075) $PN 1
J 0
(-7215 9055);
DISPLAY 0.787234 (-7215 9055);
PAINT MONO (-7215 9055);
DISPLAY INVISIBLE (-7215 9055);
FORCEPROP 1 LASTPIN (-7225 8875) $PN 2
J 0
(-7215 8855);
DISPLAY 0.787234 (-7215 8855);
PAINT MONO (-7215 8855);
DISPLAY INVISIBLE (-7215 8855);
FORCEADD GND..1
(-7225 8750);
FORCEPROP 3 LASTPIN (-7225 8800) SIG_NAME GND\g
J 0
(-7215 8810);
DISPLAY 0.659574 (-7215 8810);
PAINT MONO (-7215 8810);
DISPLAY INVISIBLE (-7215 8810);
FORCEPROP 1 LAST HDL_POWER GND
J 0
(-7225 8900);
DISPLAY 0.872340 (-7225 8900);
PAINT GREEN (-7225 8900);
DISPLAY INVISIBLE (-7225 8900);
FORCEPROP 1 LAST SIZE 1B
J 0
(-7150 8700);
DISPLAY 0.872340 (-7150 8700);
PAINT GREEN (-7150 8700);
DISPLAY INVISIBLE (-7150 8700);
FORCEPROP 2 LAST CDS_LIB logical_power
J 0
(-7225 8750);
DISPLAY INVISIBLE (-7225 8750);
FORCEPROP 1 LAST PATH I64
J 0
(-7150 8750);
DISPLAY 0.872340 (-7150 8750);
PAINT AQUA (-7150 8750);
DISPLAY INVISIBLE (-7150 8750);
FORCEADD Q_RES..1
(-7750 9650);
FORCEPROP 1 LAST PART_NUMBER CS00002JB13
J 0
(-7825 9600);
DISPLAY 0.510638 (-7825 9600);
DISPLAY INVISIBLE (-7825 9600);
FORCEPROP 2 LAST ROOM NIC1_P12V_MPS_MAM_BOM3
J 0
(-7800 9750);
DISPLAY 0.510638 (-7800 9750);
FORCEPROP 1 LAST PACK_TYPE 0402LF
J 0
(-7500 9650);
DISPLAY 0.510638 (-7500 9650);
FORCEPROP 1 LAST WATTAGE 1/16W
J 2
(-7550 9575);
DISPLAY 0.510638 (-7550 9575);
FORCEPROP 1 LAST TOLERANCE 5%
J 0
(-7575 9650);
DISPLAY 0.510638 (-7575 9650);
FORCEPROP 1 LAST VALUE 0
J 2
(-7600 9650);
DISPLAY 0.510638 (-7600 9650);
FORCEPROP 1 LAST MATERIAL CHIP
J 0
(-7825 9575);
DISPLAY 0.510638 (-7825 9575);
FORCEPROP 1 LAST $LOCATION R3834
J 0
(-7800 9700);
DISPLAY 0.510638 (-7800 9700);
FORCEPROP 1 LASTPIN (-7850 9650) $PN 1
J 0
(-7838 9662);
DISPLAY 0.510638 (-7838 9662);
PAINT MONO (-7838 9662);
FORCEPROP 1 LASTPIN (-7650 9650) $PN 2
J 0
(-7688 9662);
DISPLAY 0.510638 (-7688 9662);
PAINT MONO (-7688 9662);
FORCEPROP 2 LAST ROOM1 NIC1_P12V_MPS_TIC_BOM4
J 0
(-7800 9800);
DISPLAY 1.021277 (-7800 9800);
DISPLAY INVISIBLE (-7800 9800);
FORCEPROP 2 LAST CDS_LIB pure_quanta
J 0
(-7750 9650);
DISPLAY INVISIBLE (-7750 9650);
FORCEPROP 1 LAST PATH I65
J 0
(-7800 9800);
DISPLAY 0.978723 (-7800 9800);
PAINT WHITE (-7800 9800);
DISPLAY INVISIBLE (-7800 9800);
FORCEPROP 0 LAST CDS_LOCATION R3834
J 0
(-7800 9750);
DISPLAY 1.021277 (-7800 9750);
DISPLAY INVISIBLE (-7800 9750);
FORCEPROP 0 LAST $SEC 1
J 0
(-7800 9750);
DISPLAY 0.680851 (-7800 9750);
PAINT MONO (-7800 9750);
DISPLAY INVISIBLE (-7800 9750);
FORCEPROP 0 LAST CDS_SEC 1
J 0
(-7800 9750);
DISPLAY 1.021277 (-7800 9750);
DISPLAY INVISIBLE (-7800 9750);
FORCEADD GND..1
(-7625 9400);
FORCEPROP 3 LASTPIN (-7625 9450) SIG_NAME GND\g
J 0
(-7615 9460);
DISPLAY 0.659574 (-7615 9460);
PAINT MONO (-7615 9460);
DISPLAY INVISIBLE (-7615 9460);
FORCEPROP 1 LAST HDL_POWER GND
J 0
(-7625 9550);
DISPLAY 0.872340 (-7625 9550);
PAINT GREEN (-7625 9550);
DISPLAY INVISIBLE (-7625 9550);
FORCEPROP 2 LAST CDS_LIB logical_power
J 0
(-7625 9400);
DISPLAY INVISIBLE (-7625 9400);
FORCEPROP 1 LAST SIZE 1B
J 0
(-7550 9350);
DISPLAY 0.872340 (-7550 9350);
PAINT GREEN (-7550 9350);
DISPLAY INVISIBLE (-7550 9350);
FORCEPROP 1 LAST PATH I66
J 0
(-7550 9400);
DISPLAY 0.872340 (-7550 9400);
PAINT AQUA (-7550 9400);
DISPLAY INVISIBLE (-7550 9400);
FORCEADD GND..1
(-7300 9825);
FORCEPROP 3 LASTPIN (-7300 9875) SIG_NAME GND\g
J 0
(-7290 9885);
DISPLAY 0.659574 (-7290 9885);
PAINT MONO (-7290 9885);
DISPLAY INVISIBLE (-7290 9885);
FORCEPROP 1 LAST HDL_POWER GND
J 0
(-7300 9975);
DISPLAY 0.872340 (-7300 9975);
PAINT GREEN (-7300 9975);
DISPLAY INVISIBLE (-7300 9975);
FORCEPROP 1 LAST SIZE 1B
J 0
(-7225 9775);
DISPLAY 0.872340 (-7225 9775);
PAINT GREEN (-7225 9775);
DISPLAY INVISIBLE (-7225 9775);
FORCEPROP 2 LAST CDS_LIB logical_power
J 0
(-7300 9825);
DISPLAY INVISIBLE (-7300 9825);
FORCEPROP 1 LAST PATH I67
J 0
(-7225 9825);
DISPLAY 0.872340 (-7225 9825);
PAINT AQUA (-7225 9825);
DISPLAY INVISIBLE (-7225 9825);
FORCEADD Q_CAP..1
(-7300 10050);
FORCEPROP 1 LAST PART_NUMBER CH5104KEB02
J 0
(-7250 9900);
DISPLAY 0.510638 (-7250 9900);
DISPLAY INVISIBLE (-7250 9900);
FORCEPROP 2 LAST ROOM NIC1_P12V_MPS_MAM_BOM3
J 0
(-7250 10200);
DISPLAY 0.510638 (-7250 10200);
FORCEPROP 1 LAST PACK_TYPE C0402
J 0
(-7250 9950);
DISPLAY 0.510638 (-7250 9950);
FORCEPROP 1 LAST VALUE 1UF
J 0
(-7250 10100);
DISPLAY 0.510638 (-7250 10100);
FORCEPROP 1 LAST VOLTAGE 25V
J 0
(-7250 10050);
DISPLAY 0.510638 (-7250 10050);
FORCEPROP 1 LAST MATERIAL X6S
J 0
(-7250 10000);
DISPLAY 0.510638 (-7250 10000);
FORCEPROP 1 LAST LOCATION PC2154
J 0
(-7250 10150);
DISPLAY 0.510638 (-7250 10150);
FORCEPROP 2 LAST ROOM1 NIC1_P12V_MPS_TIC_BOM4
J 0
(-7250 10250);
DISPLAY 1.021277 (-7250 10250);
DISPLAY INVISIBLE (-7250 10250);
FORCEPROP 2 LAST CDS_LIB pure_quanta
J 0
(-7300 10050);
DISPLAY INVISIBLE (-7300 10050);
FORCEPROP 1 LAST TOLERANCE 10%
J 0
(-7250 10000);
DISPLAY 0.638298 (-7250 10000);
DISPLAY INVISIBLE (-7250 10000);
FORCEPROP 1 LAST PATH I68
J 0
(-7250 10200);
DISPLAY 0.978723 (-7250 10200);
PAINT WHITE (-7250 10200);
DISPLAY INVISIBLE (-7250 10200);
FORCEPROP 0 LAST $SEC 1
J 0
(-7245 10192);
DISPLAY INVISIBLE (-7245 10192);
FORCEPROP 0 LAST CDS_SEC 1
J 0
(-7245 10192);
DISPLAY INVISIBLE (-7245 10192);
FORCEPROP 1 LASTPIN (-7300 10150) $PN 1
J 0
(-7290 10130);
DISPLAY 0.787234 (-7290 10130);
PAINT MONO (-7290 10130);
DISPLAY INVISIBLE (-7290 10130);
FORCEPROP 1 LASTPIN (-7300 9950) $PN 2
J 0
(-7290 9930);
DISPLAY 0.787234 (-7290 9930);
PAINT MONO (-7290 9930);
DISPLAY INVISIBLE (-7290 9930);
FORCEADD GND..1
(-6884 8916);
FORCEPROP 3 LASTPIN (-6884 8966) SIG_NAME GND\g
J 0
(-6874 8976);
DISPLAY 0.659574 (-6874 8976);
PAINT MONO (-6874 8976);
DISPLAY INVISIBLE (-6874 8976);
FORCEPROP 1 LAST HDL_POWER GND
J 0
(-6884 9066);
DISPLAY 0.872340 (-6884 9066);
PAINT GREEN (-6884 9066);
DISPLAY INVISIBLE (-6884 9066);
FORCEPROP 1 LAST SIZE 1B
J 0
(-6809 8866);
DISPLAY 0.872340 (-6809 8866);
PAINT GREEN (-6809 8866);
DISPLAY INVISIBLE (-6809 8866);
FORCEPROP 2 LAST CDS_LIB logical_power
J 0
(-6884 8916);
DISPLAY INVISIBLE (-6884 8916);
FORCEPROP 1 LAST PATH I69
J 0
(-6809 8916);
DISPLAY 0.872340 (-6809 8916);
PAINT AQUA (-6809 8916);
DISPLAY INVISIBLE (-6809 8916);
FORCEADD RS31312R..1
(-6425 9525);
FORCEPROP 1 LAST PART_NUMBER AL031312000
J 0
(-6672 10189);
DISPLAY 0.723404 (-6672 10189);
PAINT GREEN (-6672 10189);
DISPLAY INVISIBLE (-6672 10189);
FORCEPROP 1 LAST MATERIAL IC
J 0
(-6672 10062);
DISPLAY 0.723404 (-6672 10062);
PAINT GREEN (-6672 10062);
FORCEPROP 2 LAST ROOM NIC1_P12V_MPS_MAM_BOM3
J 0
(-6675 10250);
DISPLAY 0.510638 (-6675 10250);
FORCEPROP 2 LAST VALUE RS31312R
J 0
(-6675 10125);
DISPLAY 0.510638 (-6675 10125);
FORCEPROP 1 LAST LOCATION PU204
J 0
(-6672 10336);
DISPLAY 0.723404 (-6672 10336);
PAINT GREEN (-6672 10336);
FORCEPROP 0 LASTPIN (-6025 9400) $PN 12
J 0
(-6015 9410);
DISPLAY 0.680851 (-6015 9410);
PAINT MONO (-6015 9410);
FORCEPROP 0 LASTPIN (-6825 9650) $PN 1
J 2
(-6835 9660);
DISPLAY 0.680851 (-6835 9660);
PAINT MONO (-6835 9660);
FORCEPROP 0 LASTPIN (-6825 9450) $PN 3
J 2
(-6835 9460);
DISPLAY 0.680851 (-6835 9460);
PAINT MONO (-6835 9460);
FORCEPROP 0 LASTPIN (-6025 9150) $PN 9
J 0
(-6015 9160);
DISPLAY 0.680851 (-6015 9160);
PAINT MONO (-6015 9160);
FORCEPROP 0 LASTPIN (-6825 9050) $PN 7
J 2
(-6835 9060);
DISPLAY 0.680851 (-6835 9060);
PAINT MONO (-6835 9060);
FORCEPROP 0 LASTPIN (-6025 9050) $PN 8
J 0
(-6015 9060);
DISPLAY 0.680851 (-6015 9060);
PAINT MONO (-6015 9060);
FORCEPROP 0 LASTPIN (-6825 9250) $PN 5
J 2
(-6835 9260);
DISPLAY 0.680851 (-6835 9260);
PAINT MONO (-6835 9260);
FORCEPROP 0 LASTPIN (-6825 9550) $PN 2
J 2
(-6835 9560);
DISPLAY 0.680851 (-6835 9560);
PAINT MONO (-6835 9560);
FORCEPROP 0 LASTPIN (-6025 9300) $PN 11
J 0
(-6015 9310);
DISPLAY 0.680851 (-6015 9310);
PAINT MONO (-6015 9310);
FORCEPROP 0 LASTPIN (-6025 10000) $PN 10
J 0
(-6015 10010);
DISPLAY 0.680851 (-6015 10010);
PAINT MONO (-6015 10010);
FORCEPROP 0 LASTPIN (-6825 9150) $PN 6
J 2
(-6835 9160);
DISPLAY 0.680851 (-6835 9160);
PAINT MONO (-6835 9160);
FORCEPROP 0 LASTPIN (-6825 9350) $PN 4
J 2
(-6835 9360);
DISPLAY 0.680851 (-6835 9360);
PAINT MONO (-6835 9360);
FORCEPROP 0 LASTPIN (-6825 10000) $PN 21_22
J 2
(-6835 10010);
DISPLAY 0.680851 (-6835 10010);
PAINT MONO (-6835 10010);
FORCEPROP 0 LASTPIN (-6825 9950) $PN 23
J 2
(-6835 9960);
DISPLAY 0.680851 (-6835 9960);
PAINT MONO (-6835 9960);
FORCEPROP 0 LASTPIN (-6825 9900) $PN 24
J 2
(-6835 9910);
DISPLAY 0.680851 (-6835 9910);
PAINT MONO (-6835 9910);
FORCEPROP 0 LASTPIN (-6825 9850) $PN 25
J 2
(-6835 9860);
DISPLAY 0.680851 (-6835 9860);
PAINT MONO (-6835 9860);
FORCEPROP 0 LASTPIN (-6825 9800) $PN 26
J 2
(-6835 9810);
DISPLAY 0.680851 (-6835 9810);
PAINT MONO (-6835 9810);
FORCEPROP 0 LASTPIN (-6025 9500) $PN 13
J 0
(-6015 9510);
DISPLAY 0.680851 (-6015 9510);
PAINT MONO (-6015 9510);
FORCEPROP 0 LASTPIN (-6025 9550) $PN 14
J 0
(-6015 9560);
DISPLAY 0.680851 (-6015 9560);
PAINT MONO (-6015 9560);
FORCEPROP 0 LASTPIN (-6025 9600) $PN 15
J 0
(-6015 9610);
DISPLAY 0.680851 (-6015 9610);
PAINT MONO (-6015 9610);
FORCEPROP 0 LASTPIN (-6025 9650) $PN 16
J 0
(-6015 9660);
DISPLAY 0.680851 (-6015 9660);
PAINT MONO (-6015 9660);
FORCEPROP 0 LASTPIN (-6025 9700) $PN 17
J 0
(-6015 9710);
DISPLAY 0.680851 (-6015 9710);
PAINT MONO (-6015 9710);
FORCEPROP 0 LASTPIN (-6025 9750) $PN 18
J 0
(-6015 9760);
DISPLAY 0.680851 (-6015 9760);
PAINT MONO (-6015 9760);
FORCEPROP 0 LASTPIN (-6025 9800) $PN 19
J 0
(-6015 9810);
DISPLAY 0.680851 (-6015 9810);
PAINT MONO (-6015 9810);
FORCEPROP 0 LASTPIN (-6025 9850) $PN 20
J 0
(-6015 9860);
DISPLAY 0.680851 (-6015 9860);
PAINT MONO (-6015 9860);
FORCEPROP 0 LAST PART_TYPE SMLF
J 0
(-6678 10310);
DISPLAY 1.021277 (-6678 10310);
DISPLAY INVISIBLE (-6678 10310);
FORCEPROP 2 LAST CDS_LIB pure_quanta
J 0
(-6425 9525);
DISPLAY INVISIBLE (-6425 9525);
FORCEPROP 1 LAST NEEDS_NO_SIZE TRUE
J 0
(-6425 9525);
DISPLAY 0.723404 (-6425 9525);
PAINT GREEN (-6425 9525);
DISPLAY INVISIBLE (-6425 9525);
FORCEPROP 1 LAST CDS_LMAN_SYM_OUTLINE -250,525,250,-525
J 0
(-6425 9525);
DISPLAY 0.468085 (-6425 9525);
PAINT GREEN (-6425 9525);
DISPLAY INVISIBLE (-6425 9525);
FORCEPROP 2 LAST ROOM1 NIC1_P12V_MPS_TIC_BOM4
J 0
(-6675 10350);
DISPLAY 1.021277 (-6675 10350);
DISPLAY INVISIBLE (-6675 10350);
FORCEPROP 1 LAST PATH I70
J 0
(-6425 9525);
DISPLAY 0.723404 (-6425 9525);
PAINT GREEN (-6425 9525);
DISPLAY INVISIBLE (-6425 9525);
FORCEPROP 0 LAST $SEC 1
J 0
(-6650 10375);
DISPLAY 0.680851 (-6650 10375);
PAINT MONO (-6650 10375);
DISPLAY INVISIBLE (-6650 10375);
FORCEPROP 0 LAST CDS_SEC 1
J 0
(-6650 10375);
DISPLAY 1.021277 (-6650 10375);
DISPLAY INVISIBLE (-6650 10375);
FORCEADD UNIVERSAL_POWER..1
(-7300 10400);
FORCEPROP 3 LASTPIN (-7300 10350) SIG_NAME P12V_AUX\g
J 0
(-7290 10360);
DISPLAY 0.659574 (-7290 10360);
PAINT MONO (-7290 10360);
DISPLAY INVISIBLE (-7290 10360);
FORCEPROP 1 LAST HDL_POWER P12V_AUX
J 1
(-7300 10450);
DISPLAY 0.872340 (-7300 10450);
PAINT GREEN (-7300 10450);
FORCEPROP 2 LAST CDS_LIB logical_power
J 0
(-7300 10400);
DISPLAY INVISIBLE (-7300 10400);
FORCEPROP 1 LAST PATH I71
J 0
(-7250 10425);
DISPLAY 0.872340 (-7250 10425);
PAINT AQUA (-7250 10425);
DISPLAY INVISIBLE (-7250 10425);
FORCEADD Q_RES..2
(-5800 8775);
FORCEPROP 1 LAST PART_NUMBER CS31742FB04
J 0
(-5760 8650);
DISPLAY 0.510638 (-5760 8650);
DISPLAY INVISIBLE (-5760 8650);
FORCEPROP 1 LAST PACK_TYPE 0402LF
J 0
(-5760 8600);
DISPLAY 0.510638 (-5760 8600);
FORCEPROP 1 LAST VALUE 17.4K
J 0
(-5755 8850);
DISPLAY 0.510638 (-5755 8850);
FORCEPROP 1 LAST MATERIAL CHIP
J 0
(-5760 8700);
DISPLAY 0.510638 (-5760 8700);
FORCEPROP 1 LAST WATTAGE 1/16W
J 0
(-5760 8750);
DISPLAY 0.510638 (-5760 8750);
FORCEPROP 1 LAST TOLERANCE 1%
J 0
(-5755 8800);
DISPLAY 0.510638 (-5755 8800);
FORCEPROP 2 LAST ROOM NIC1_P12V_MPS_MAM_BOM3
J 0
(-5750 8950);
DISPLAY 0.510638 (-5750 8950);
FORCEPROP 1 LAST LOCATION PR3837
J 0
(-5755 8900);
DISPLAY 0.510638 (-5755 8900);
FORCEPROP 1 LASTPIN (-5800 8875) $PN 1
J 0
(-5795 8837);
DISPLAY 0.510638 (-5795 8837);
PAINT MONO (-5795 8837);
FORCEPROP 1 LASTPIN (-5800 8675) $PN 2
J 0
(-5795 8685);
DISPLAY 0.510638 (-5795 8685);
PAINT MONO (-5795 8685);
FORCEPROP 2 LAST ROOM1 NIC1_P12V_MPS_TIC_BOM4
J 0
(-5750 9000);
DISPLAY 1.021277 (-5750 9000);
DISPLAY INVISIBLE (-5750 9000);
FORCEPROP 2 LAST CDS_LIB pure_quanta
J 0
(-5800 8775);
DISPLAY INVISIBLE (-5800 8775);
FORCEPROP 1 LAST PATH I72
J 0
(-5750 8950);
DISPLAY 0.978723 (-5750 8950);
PAINT WHITE (-5750 8950);
DISPLAY INVISIBLE (-5750 8950);
FORCEPROP 0 LAST $SEC 1
J 0
(-5750 8950);
DISPLAY 0.680851 (-5750 8950);
PAINT MONO (-5750 8950);
DISPLAY INVISIBLE (-5750 8950);
FORCEPROP 0 LAST CDS_SEC 1
J 0
(-5750 8950);
DISPLAY 1.021277 (-5750 8950);
DISPLAY INVISIBLE (-5750 8950);
FORCEADD GND..1
(-5350 8375);
FORCEPROP 3 LASTPIN (-5350 8425) SIG_NAME GND\g
J 0
(-5340 8435);
DISPLAY 0.659574 (-5340 8435);
PAINT MONO (-5340 8435);
DISPLAY INVISIBLE (-5340 8435);
FORCEPROP 1 LAST HDL_POWER GND
J 0
(-5350 8525);
DISPLAY 0.872340 (-5350 8525);
PAINT GREEN (-5350 8525);
DISPLAY INVISIBLE (-5350 8525);
FORCEPROP 2 LAST CDS_LIB logical_power
J 0
(-5350 8375);
DISPLAY INVISIBLE (-5350 8375);
FORCEPROP 1 LAST SIZE 1B
J 0
(-5275 8325);
DISPLAY 0.872340 (-5275 8325);
PAINT GREEN (-5275 8325);
DISPLAY INVISIBLE (-5275 8325);
FORCEPROP 1 LAST PATH I73
J 0
(-5275 8375);
DISPLAY 0.872340 (-5275 8375);
PAINT AQUA (-5275 8375);
DISPLAY INVISIBLE (-5275 8375);
FORCEADD Q_CAP..1
(-5350 8775);
FORCEPROP 1 LAST PART_NUMBER CH4106K1B01
J 0
(-5295 8667);
DISPLAY 0.510638 (-5295 8667);
DISPLAY INVISIBLE (-5295 8667);
FORCEPROP 1 LAST PACK_TYPE C0402
J 0
(-5295 8717);
DISPLAY 0.510638 (-5295 8717);
FORCEPROP 1 LAST VOLTAGE 50V
J 0
(-5295 8767);
DISPLAY 0.510638 (-5295 8767);
FORCEPROP 1 LAST MATERIAL X7R
J 0
(-5275 8600);
DISPLAY 0.510638 (-5275 8600);
FORCEPROP 1 LAST VALUE 100NF
J 0
(-5300 8825);
DISPLAY 0.510638 (-5300 8825);
FORCEPROP 2 LAST ROOM NIC1_P12V_MPS_MAM_BOM3
J 0
(-5300 8925);
DISPLAY 0.510638 (-5300 8925);
FORCEPROP 1 LAST LOCATION PC2156
J 0
(-5300 8875);
DISPLAY 0.510638 (-5300 8875);
FORCEPROP 2 LAST ROOM1 NIC1_P12V_MPS_TIC_BOM4
J 0
(-5300 8975);
DISPLAY 1.021277 (-5300 8975);
DISPLAY INVISIBLE (-5300 8975);
FORCEPROP 2 LAST CDS_LIB pure_quanta
J 0
(-5350 8775);
DISPLAY INVISIBLE (-5350 8775);
FORCEPROP 1 LAST TOLERANCE 10%
J 0
(-5300 8725);
DISPLAY 0.638298 (-5300 8725);
DISPLAY INVISIBLE (-5300 8725);
FORCEPROP 1 LAST PATH I74
J 0
(-5300 8925);
DISPLAY 0.978723 (-5300 8925);
PAINT WHITE (-5300 8925);
DISPLAY INVISIBLE (-5300 8925);
FORCEPROP 0 LAST $SEC 1
J 0
(-5300 8925);
DISPLAY INVISIBLE (-5300 8925);
FORCEPROP 0 LAST CDS_SEC 1
J 0
(-5300 8925);
DISPLAY INVISIBLE (-5300 8925);
FORCEPROP 1 LASTPIN (-5350 8875) $PN 1
J 0
(-5340 8855);
DISPLAY 0.787234 (-5340 8855);
PAINT MONO (-5340 8855);
DISPLAY INVISIBLE (-5340 8855);
FORCEPROP 1 LASTPIN (-5350 8675) $PN 2
J 0
(-5340 8655);
DISPLAY 0.787234 (-5340 8655);
PAINT MONO (-5340 8655);
DISPLAY INVISIBLE (-5340 8655);
FORCEADD Q_RES..1
(-5425 9150);
FORCEPROP 1 LAST PART_NUMBER CS31002FB08
J 0
(-5525 9175);
DISPLAY 0.510638 (-5525 9175);
DISPLAY INVISIBLE (-5525 9175);
FORCEPROP 1 LAST TOLERANCE 1%
J 0
(-5375 9125);
DISPLAY 0.510638 (-5375 9125);
FORCEPROP 1 LAST VALUE 10K
J 2
(-5450 9125);
DISPLAY 0.510638 (-5450 9125);
FORCEPROP 1 LAST MATERIAL CHIP
J 0
(-5300 9125);
DISPLAY 0.510638 (-5300 9125);
FORCEPROP 1 LAST PACK_TYPE 0402LF
J 0
(-5275 9175);
DISPLAY 0.510638 (-5275 9175);
FORCEPROP 2 LAST ROOM NIC1_P12V_MPS_MAM_BOM3
J 0
(-5500 9250);
DISPLAY 0.510638 (-5500 9250);
FORCEPROP 1 LAST WATTAGE 1/16W
J 2
(-5100 9125);
DISPLAY 0.510638 (-5100 9125);
FORCEPROP 1 LAST LOCATION PR3839
J 0
(-5500 9200);
DISPLAY 0.510638 (-5500 9200);
FORCEPROP 2 LAST ROOM1 NIC1_P12V_MPS_TIC_BOM4
J 0
(-5500 9300);
DISPLAY 1.021277 (-5500 9300);
DISPLAY INVISIBLE (-5500 9300);
FORCEPROP 2 LAST CDS_LIB pure_quanta
J 0
(-5425 9150);
DISPLAY INVISIBLE (-5425 9150);
FORCEPROP 1 LAST PATH I75
J 0
(-5475 9300);
DISPLAY 0.978723 (-5475 9300);
PAINT WHITE (-5475 9300);
DISPLAY INVISIBLE (-5475 9300);
FORCEPROP 0 LAST $SEC 1
J 0
(-5525 9225);
DISPLAY 0.680851 (-5525 9225);
PAINT MONO (-5525 9225);
DISPLAY INVISIBLE (-5525 9225);
FORCEPROP 0 LAST CDS_SEC 1
J 0
(-5475 9300);
DISPLAY INVISIBLE (-5475 9300);
FORCEPROP 1 LASTPIN (-5525 9150) $PN 1
J 0
(-5513 9162);
DISPLAY 0.787234 (-5513 9162);
PAINT MONO (-5513 9162);
DISPLAY INVISIBLE (-5513 9162);
FORCEPROP 1 LASTPIN (-5325 9150) $PN 2
J 0
(-5363 9162);
DISPLAY 0.787234 (-5363 9162);
PAINT MONO (-5363 9162);
DISPLAY INVISIBLE (-5363 9162);
FORCEADD Q_RES..2
(-5950 10225);
FORCEPROP 1 LAST PART_NUMBER CS31002FB08
J 0
(-5920 10142);
DISPLAY 0.510638 (-5920 10142);
DISPLAY INVISIBLE (-5920 10142);
FORCEPROP 1 LAST VALUE 10K
J 0
(-5915 10342);
DISPLAY 0.510638 (-5915 10342);
FORCEPROP 1 LAST TOLERANCE 1%
J 0
(-5915 10292);
DISPLAY 0.510638 (-5915 10292);
FORCEPROP 2 LAST ROOM NIC1_P12V_MPS_MAM_BOM3
J 0
(-5900 10425);
DISPLAY 0.510638 (-5900 10425);
FORCEPROP 1 LAST MATERIAL CHIP
J 0
(-5920 10192);
DISPLAY 0.510638 (-5920 10192);
FORCEPROP 1 LAST WATTAGE 1/16W
J 0
(-5920 10242);
DISPLAY 0.510638 (-5920 10242);
FORCEPROP 1 LAST PACK_TYPE 0402LF
J 0
(-5920 10092);
DISPLAY 0.510638 (-5920 10092);
FORCEPROP 1 LAST $LOCATION R4532
J 0
(-5915 10392);
DISPLAY 0.510638 (-5915 10392);
FORCEPROP 1 LASTPIN (-5950 10325) $PN 1
J 0
(-5945 10287);
DISPLAY 0.510638 (-5945 10287);
PAINT MONO (-5945 10287);
FORCEPROP 1 LASTPIN (-5950 10125) $PN 2
J 0
(-5945 10135);
DISPLAY 0.510638 (-5945 10135);
PAINT MONO (-5945 10135);
FORCEPROP 2 LAST ROOM1 NIC1_P12V_MPS_TIC_BOM4
J 0
(-5900 10475);
DISPLAY 1.021277 (-5900 10475);
DISPLAY INVISIBLE (-5900 10475);
FORCEPROP 2 LAST CDS_LIB pure_quanta
J 0
(-5950 10225);
DISPLAY INVISIBLE (-5950 10225);
FORCEPROP 1 LAST PATH I76
J 0
(-5900 10400);
DISPLAY 0.978723 (-5900 10400);
PAINT WHITE (-5900 10400);
DISPLAY INVISIBLE (-5900 10400);
FORCEPROP 0 LAST CDS_LOCATION R4532
J 0
(-5900 10425);
DISPLAY 1.021277 (-5900 10425);
DISPLAY INVISIBLE (-5900 10425);
FORCEPROP 0 LAST $SEC 1
J 0
(-5895 10442);
DISPLAY 0.680851 (-5895 10442);
PAINT MONO (-5895 10442);
DISPLAY INVISIBLE (-5895 10442);
FORCEPROP 0 LAST CDS_SEC 1
J 0
(-5900 10400);
DISPLAY INVISIBLE (-5900 10400);
FORCEADD Q_RES..2
(-5425 9625);
FORCEPROP 1 LAST PART_NUMBER CS11002FB07
J 0
(-5385 9450);
DISPLAY 0.510638 (-5385 9450);
DISPLAY INVISIBLE (-5385 9450);
FORCEPROP 1 LAST VALUE 100
J 0
(-5380 9700);
DISPLAY 0.510638 (-5380 9700);
FORCEPROP 1 LAST TOLERANCE 1%
J 0
(-5380 9650);
DISPLAY 0.510638 (-5380 9650);
FORCEPROP 1 LAST MATERIAL EMPTY
J 0
(-5385 9550);
DISPLAY 0.510638 (-5385 9550);
PAINT RED (-5385 9550);
FORCEPROP 1 LAST WATTAGE 1/16W
J 0
(-5385 9600);
DISPLAY 0.510638 (-5385 9600);
FORCEPROP 1 LAST PACK_TYPE 0402LF
J 0
(-5385 9500);
DISPLAY 0.510638 (-5385 9500);
FORCEPROP 1 LAST LOCATION PR3838
J 0
(-5375 9750);
DISPLAY 0.510638 (-5375 9750);
FORCEPROP 1 LASTPIN (-5425 9725) $PN 1
J 0
(-5420 9687);
DISPLAY 0.510638 (-5420 9687);
PAINT MONO (-5420 9687);
FORCEPROP 1 LASTPIN (-5425 9525) $PN 2
J 0
(-5420 9535);
DISPLAY 0.510638 (-5420 9535);
PAINT MONO (-5420 9535);
FORCEPROP 2 LAST CDS_LIB pure_quanta
J 0
(-5425 9625);
DISPLAY INVISIBLE (-5425 9625);
FORCEPROP 1 LAST PATH I77
J 0
(-5375 9800);
DISPLAY 0.978723 (-5375 9800);
PAINT WHITE (-5375 9800);
DISPLAY INVISIBLE (-5375 9800);
FORCEPROP 0 LAST $SEC 1
J 0
(-5375 9800);
DISPLAY 0.680851 (-5375 9800);
PAINT MONO (-5375 9800);
DISPLAY INVISIBLE (-5375 9800);
FORCEPROP 0 LAST CDS_SEC 1
J 0
(-5375 9800);
DISPLAY 1.021277 (-5375 9800);
DISPLAY INVISIBLE (-5375 9800);
FORCEADD OFFPAGE..1
R 2
(-5225 9400);
PAINT AQUA (-5225 9400);
FORCEPROP 2 LAST $XR0 157 
J 0
(-5039 9400);
DISPLAY 0.638298 (-5039 9400);
PAINT MONO (-5039 9400);
FORCEPROP 1 LAST COMMENT_BODY TRUE
J 2
(-5350 9300);
DISPLAY 0.872340 (-5350 9300);
PAINT GREEN (-5350 9300);
DISPLAY INVISIBLE (-5350 9300);
FORCEPROP 1 LAST OFFPAGE TRUE
J 2
(-5550 9275);
DISPLAY 0.872340 (-5550 9275);
PAINT AQUA (-5550 9275);
DISPLAY INVISIBLE (-5550 9275);
FORCEPROP 2 LAST CDS_LIB standard
J 2
(-5225 9400);
DISPLAY INVISIBLE (-5225 9400);
FORCEPROP 2 LAST PATH I78
J 0
(-5025 9425);
DISPLAY 1.021277 (-5025 9425);
DISPLAY INVISIBLE (-5025 9425);
FORCEADD OFFPAGE..2
(-5150 10000);
PAINT AQUA (-5150 10000);
FORCEPROP 2 LAST $XR2 214 
J 0
(-4961 10036);
DISPLAY 0.638298 (-4961 10036);
PAINT MONO (-4961 10036);
FORCEPROP 2 LAST $XR1 158 
J 0
(-4961 9964);
DISPLAY 0.638298 (-4961 9964);
PAINT MONO (-4961 9964);
FORCEPROP 2 LAST $XR0 156 
J 0
(-4961 10000);
DISPLAY 0.638298 (-4961 10000);
PAINT MONO (-4961 10000);
FORCEPROP 1 LAST COMMENT_BODY TRUE
J 0
(-5195 9905);
DISPLAY 0.872340 (-5195 9905);
PAINT GREEN (-5195 9905);
DISPLAY INVISIBLE (-5195 9905);
FORCEPROP 1 LAST OFFPAGE TRUE
J 0
(-4825 9875);
DISPLAY 0.872340 (-4825 9875);
PAINT AQUA (-4825 9875);
DISPLAY INVISIBLE (-4825 9875);
FORCEPROP 2 LAST CDS_LIB standard
J 0
(-5150 10000);
DISPLAY INVISIBLE (-5150 10000);
FORCEPROP 2 LAST PATH I79
J 0
(-4950 10025);
DISPLAY 1.021277 (-4950 10025);
DISPLAY INVISIBLE (-4950 10025);
FORCEADD VCCAUX15..1
(-4800 9200);
FORCEPROP 3 LASTPIN (-4800 9150) SIG_NAME P3V3_AUX\g
J 0
(-4790 9160);
DISPLAY 0.659574 (-4790 9160);
PAINT MONO (-4790 9160);
DISPLAY INVISIBLE (-4790 9160);
FORCEPROP 1 LAST HDL_POWER P3V3_AUX
J 1
(-4800 9225);
DISPLAY 0.510638 (-4800 9225);
PAINT GREEN (-4800 9225);
FORCEPROP 2 LAST CDS_LIB logical_power
J 0
(-4800 9200);
DISPLAY INVISIBLE (-4800 9200);
FORCEPROP 1 LAST PATH I80
J 0
(-4750 9225);
DISPLAY 0.872340 (-4750 9225);
PAINT AQUA (-4750 9225);
DISPLAY INVISIBLE (-4750 9225);
FORCEADD Q_RES..1
(-4000 8450);
FORCEPROP 1 LAST PART_NUMBER CS00002JB13
J 0
(-4175 8400);
DISPLAY 0.510638 (-4175 8400);
DISPLAY INVISIBLE (-4175 8400);
FORCEPROP 0 LAST ROOM1 NIC1_P12V_MPS_TIC_BOM4
J 0
(-4300 8275);
DISPLAY 0.510638 (-4300 8275);
FORCEPROP 1 LAST WATTAGE 1/16W
J 2
(-4200 8400);
DISPLAY 0.510638 (-4200 8400);
FORCEPROP 1 LAST PACK_TYPE 0402LF
J 0
(-3850 8400);
DISPLAY 0.510638 (-3850 8400);
FORCEPROP 1 LAST TOLERANCE 5%
J 0
(-3825 8450);
DISPLAY 0.510638 (-3825 8450);
FORCEPROP 1 LAST VALUE 0
J 2
(-3850 8450);
DISPLAY 0.510638 (-3850 8450);
FORCEPROP 1 LAST MATERIAL CHIP
J 0
(-4225 8450);
DISPLAY 0.510638 (-4225 8450);
PAINT RED (-4225 8450);
FORCEPROP 1 LAST $LOCATION R3872
J 0
(-4050 8500);
DISPLAY 0.510638 (-4050 8500);
FORCEPROP 1 LASTPIN (-4100 8450) $PN 1
J 0
(-4088 8462);
DISPLAY 0.510638 (-4088 8462);
PAINT MONO (-4088 8462);
FORCEPROP 1 LASTPIN (-3900 8450) $PN 2
J 0
(-3938 8462);
DISPLAY 0.510638 (-3938 8462);
PAINT MONO (-3938 8462);
FORCEPROP 1 LAST PATH I81
J 0
(-4050 8600);
DISPLAY 0.978723 (-4050 8600);
PAINT WHITE (-4050 8600);
DISPLAY INVISIBLE (-4050 8600);
FORCEPROP 2 LAST CDS_LIB pure_quanta
J 0
(-4000 8450);
DISPLAY INVISIBLE (-4000 8450);
FORCEPROP 0 LAST CDS_LOCATION R3872
J 0
(-4050 8550);
DISPLAY 1.021277 (-4050 8550);
DISPLAY INVISIBLE (-4050 8550);
FORCEPROP 0 LAST $SEC 1
J 0
(-4050 8550);
DISPLAY 0.680851 (-4050 8550);
PAINT MONO (-4050 8550);
DISPLAY INVISIBLE (-4050 8550);
FORCEPROP 0 LAST CDS_SEC 1
J 0
(-4050 8550);
DISPLAY 1.021277 (-4050 8550);
DISPLAY INVISIBLE (-4050 8550);
FORCEADD Q_RES..1
(-4000 8625);
FORCEPROP 1 LAST PART_NUMBER CS00002JB13
J 0
(-4175 8575);
DISPLAY 0.510638 (-4175 8575);
DISPLAY INVISIBLE (-4175 8575);
FORCEPROP 1 LAST TOLERANCE 5%
J 0
(-3825 8625);
DISPLAY 0.510638 (-3825 8625);
FORCEPROP 1 LAST VALUE 0
J 2
(-3850 8625);
DISPLAY 0.510638 (-3850 8625);
FORCEPROP 1 LAST MATERIAL EMPTY
J 0
(-4225 8625);
DISPLAY 0.510638 (-4225 8625);
FORCEPROP 1 LAST WATTAGE 1/16W
J 2
(-4200 8575);
DISPLAY 0.510638 (-4200 8575);
FORCEPROP 2 LAST ROOM NIC1_P12V_MPS_MAM_BOM3
J 0
(-4275 8725);
DISPLAY 0.510638 (-4275 8725);
FORCEPROP 1 LAST PACK_TYPE 0402LF
J 0
(-3850 8575);
DISPLAY 0.510638 (-3850 8575);
FORCEPROP 1 LAST $LOCATION R3871
J 0
(-4050 8675);
DISPLAY 0.510638 (-4050 8675);
FORCEPROP 1 LASTPIN (-4100 8625) $PN 1
J 0
(-4088 8637);
DISPLAY 0.510638 (-4088 8637);
PAINT MONO (-4088 8637);
FORCEPROP 1 LASTPIN (-3900 8625) $PN 2
J 0
(-3938 8637);
DISPLAY 0.510638 (-3938 8637);
PAINT MONO (-3938 8637);
FORCEPROP 1 LAST PATH I82
J 0
(-4050 8775);
DISPLAY 0.978723 (-4050 8775);
PAINT WHITE (-4050 8775);
DISPLAY INVISIBLE (-4050 8775);
FORCEPROP 2 LAST CDS_LIB pure_quanta
J 0
(-4000 8625);
DISPLAY INVISIBLE (-4000 8625);
FORCEPROP 0 LAST CDS_LOCATION R3871
J 0
(-4050 8725);
DISPLAY 1.021277 (-4050 8725);
DISPLAY INVISIBLE (-4050 8725);
FORCEPROP 0 LAST $SEC 1
J 0
(-4050 8725);
DISPLAY 0.680851 (-4050 8725);
PAINT MONO (-4050 8725);
DISPLAY INVISIBLE (-4050 8725);
FORCEPROP 0 LAST CDS_SEC 1
J 0
(-4050 8725);
DISPLAY 1.021277 (-4050 8725);
DISPLAY INVISIBLE (-4050 8725);
FORCEADD Q_RES..2
(-4425 9125);
FORCEPROP 1 LAST PART_NUMBER CS31002FB08
J 0
(-4385 9000);
DISPLAY 0.510638 (-4385 9000);
DISPLAY INVISIBLE (-4385 9000);
FORCEPROP 1 LAST TOLERANCE 1%
J 0
(-4380 9150);
DISPLAY 0.510638 (-4380 9150);
FORCEPROP 1 LAST VALUE 10K
J 0
(-4380 9200);
DISPLAY 0.510638 (-4380 9200);
FORCEPROP 1 LAST MATERIAL CHIP
J 0
(-4385 9050);
DISPLAY 0.510638 (-4385 9050);
FORCEPROP 2 LAST ROOM NIC1_P12V_MPS_MAM_BOM3
J 0
(-4375 9300);
DISPLAY 0.510638 (-4375 9300);
FORCEPROP 1 LAST WATTAGE 1/16W
J 0
(-4385 9100);
DISPLAY 0.510638 (-4385 9100);
FORCEPROP 1 LAST PACK_TYPE 0402LF
J 0
(-4385 8950);
DISPLAY 0.510638 (-4385 8950);
FORCEPROP 1 LAST LOCATION PR3842
J 0
(-4380 9250);
DISPLAY 0.510638 (-4380 9250);
FORCEPROP 2 LAST ROOM1 NIC1_P12V_MPS_TIC_BOM4
J 0
(-4375 9350);
DISPLAY 1.021277 (-4375 9350);
DISPLAY INVISIBLE (-4375 9350);
FORCEPROP 2 LAST CDS_LIB pure_quanta
J 0
(-4425 9125);
DISPLAY INVISIBLE (-4425 9125);
FORCEPROP 1 LAST PATH I83
J 0
(-4375 9300);
DISPLAY 0.978723 (-4375 9300);
PAINT WHITE (-4375 9300);
DISPLAY INVISIBLE (-4375 9300);
FORCEPROP 0 LAST $SEC 1
J 0
(-4375 9300);
DISPLAY INVISIBLE (-4375 9300);
FORCEPROP 0 LAST CDS_SEC 1
J 0
(-4375 9300);
DISPLAY INVISIBLE (-4375 9300);
FORCEPROP 1 LASTPIN (-4425 9225) $PN 1
J 0
(-4420 9187);
DISPLAY 0.787234 (-4420 9187);
PAINT MONO (-4420 9187);
DISPLAY INVISIBLE (-4420 9187);
FORCEPROP 1 LASTPIN (-4425 9025) $PN 2
J 0
(-4420 9035);
DISPLAY 0.787234 (-4420 9035);
PAINT MONO (-4420 9035);
DISPLAY INVISIBLE (-4420 9035);
FORCEADD GND..1
(-4225 8800);
FORCEPROP 3 LASTPIN (-4225 8850) SIG_NAME GND\g
J 0
(-4215 8860);
DISPLAY 0.659574 (-4215 8860);
PAINT MONO (-4215 8860);
DISPLAY INVISIBLE (-4215 8860);
FORCEPROP 1 LAST HDL_POWER GND
J 0
(-4225 8950);
DISPLAY 0.872340 (-4225 8950);
PAINT GREEN (-4225 8950);
DISPLAY INVISIBLE (-4225 8950);
FORCEPROP 2 LAST CDS_LIB logical_power
J 0
(-4225 8800);
DISPLAY INVISIBLE (-4225 8800);
FORCEPROP 1 LAST SIZE 1B
J 0
(-4150 8750);
DISPLAY 0.872340 (-4150 8750);
PAINT GREEN (-4150 8750);
DISPLAY INVISIBLE (-4150 8750);
FORCEPROP 1 LAST PATH I84
J 0
(-4150 8800);
DISPLAY 0.872340 (-4150 8800);
PAINT AQUA (-4150 8800);
DISPLAY INVISIBLE (-4150 8800);
FORCEADD Q_RES..2
(-4825 9625);
FORCEPROP 1 LAST PART_NUMBER CS37152FB05
J 0
(-4800 9500);
DISPLAY 0.510638 (-4800 9500);
PAINT WHITE (-4800 9500);
DISPLAY INVISIBLE (-4800 9500);
FORCEPROP 1 LAST VALUE 71.5K
J 0
(-4800 9650);
DISPLAY 0.510638 (-4800 9650);
PAINT SKYBLUE (-4800 9650);
FORCEPROP 1 LAST MATERIAL EMPTY
J 0
(-4800 9450);
DISPLAY 0.510638 (-4800 9450);
PAINT RED (-4800 9450);
FORCEPROP 1 LAST TOLERANCE 1%
J 0
(-4800 9600);
DISPLAY 0.510638 (-4800 9600);
PAINT SKYBLUE (-4800 9600);
FORCEPROP 1 LAST PACK_TYPE 0402LF
J 0
(-4800 9550);
DISPLAY 0.510638 (-4800 9550);
PAINT SKYBLUE (-4800 9550);
FORCEPROP 1 LAST LOCATION PR3840
J 0
(-4800 9700);
DISPLAY 0.510638 (-4800 9700);
PAINT AQUA (-4800 9700);
FORCEPROP 1 LASTPIN (-4825 9725) $PN 1
J 0
(-4820 9687);
DISPLAY 0.510638 (-4820 9687);
PAINT MONO (-4820 9687);
FORCEPROP 1 LASTPIN (-4825 9525) $PN 2
J 0
(-4820 9535);
DISPLAY 0.510638 (-4820 9535);
PAINT MONO (-4820 9535);
FORCEPROP 2 LAST CDS_LIB pure_quanta
J 0
(-4825 9625);
DISPLAY INVISIBLE (-4825 9625);
FORCEPROP 1 LAST WATTAGE 1/16W
J 0
(-4800 9600);
DISPLAY 0.723404 (-4800 9600);
PAINT SKYBLUE (-4800 9600);
DISPLAY INVISIBLE (-4800 9600);
FORCEPROP 1 LAST PATH I85
J 0
(-4775 9800);
DISPLAY 0.978723 (-4775 9800);
PAINT WHITE (-4775 9800);
DISPLAY INVISIBLE (-4775 9800);
FORCEPROP 0 LAST $SEC 1
J 0
(-4800 9750);
DISPLAY 0.680851 (-4800 9750);
PAINT MONO (-4800 9750);
DISPLAY INVISIBLE (-4800 9750);
FORCEPROP 0 LAST CDS_SEC 1
J 0
(-4800 9750);
DISPLAY 1.021277 (-4800 9750);
DISPLAY INVISIBLE (-4800 9750);
FORCEADD Q_RES..2
(-4425 9550);
FORCEPROP 1 LAST PART_NUMBER CS41202FB05
J 0
(-4385 9425);
DISPLAY 0.510638 (-4385 9425);
DISPLAY INVISIBLE (-4385 9425);
FORCEPROP 1 LAST VALUE 120K
J 0
(-4380 9625);
DISPLAY 0.510638 (-4380 9625);
FORCEPROP 2 LAST ROOM NIC1_P12V_MPS_MAM_BOM3
J 0
(-4375 9725);
DISPLAY 0.510638 (-4375 9725);
FORCEPROP 1 LAST PACK_TYPE 0402LF
J 0
(-4385 9375);
DISPLAY 0.510638 (-4385 9375);
FORCEPROP 1 LAST MATERIAL CHIP
J 0
(-4385 9475);
DISPLAY 0.510638 (-4385 9475);
FORCEPROP 1 LAST TOLERANCE 1%
J 0
(-4380 9575);
DISPLAY 0.510638 (-4380 9575);
FORCEPROP 1 LAST WATTAGE 1/16W
J 0
(-4385 9525);
DISPLAY 0.510638 (-4385 9525);
FORCEPROP 1 LAST LOCATION PR3841
J 0
(-4380 9675);
DISPLAY 0.510638 (-4380 9675);
FORCEPROP 2 LAST ROOM1 NIC1_P12V_MPS_TIC_BOM4
J 0
(-4375 9775);
DISPLAY 1.021277 (-4375 9775);
DISPLAY INVISIBLE (-4375 9775);
FORCEPROP 2 LAST CDS_LIB pure_quanta
J 0
(-4425 9550);
DISPLAY INVISIBLE (-4425 9550);
FORCEPROP 1 LAST PATH I86
J 0
(-4375 9725);
DISPLAY 0.978723 (-4375 9725);
PAINT WHITE (-4375 9725);
DISPLAY INVISIBLE (-4375 9725);
FORCEPROP 0 LAST $SEC 1
J 0
(-4375 9725);
DISPLAY INVISIBLE (-4375 9725);
FORCEPROP 0 LAST CDS_SEC 1
J 0
(-4375 9725);
DISPLAY INVISIBLE (-4375 9725);
FORCEPROP 1 LASTPIN (-4425 9650) $PN 1
J 0
(-4420 9612);
DISPLAY 0.787234 (-4420 9612);
PAINT MONO (-4420 9612);
DISPLAY INVISIBLE (-4420 9612);
FORCEPROP 1 LASTPIN (-4425 9450) $PN 2
J 0
(-4420 9460);
DISPLAY 0.787234 (-4420 9460);
PAINT MONO (-4420 9460);
DISPLAY INVISIBLE (-4420 9460);
FORCEADD VCCAUX15..1
(-5950 10425);
FORCEPROP 3 LASTPIN (-5950 10375) SIG_NAME P3V3_AUX\g
J 0
(-5940 10385);
DISPLAY 0.659574 (-5940 10385);
PAINT MONO (-5940 10385);
DISPLAY INVISIBLE (-5940 10385);
FORCEPROP 1 LAST HDL_POWER P3V3_AUX
J 1
(-5950 10475);
DISPLAY 0.723404 (-5950 10475);
PAINT GREEN (-5950 10475);
FORCEPROP 2 LAST CDS_LIB logical_power
J 0
(-5950 10425);
DISPLAY INVISIBLE (-5950 10425);
FORCEPROP 1 LAST PATH I87
J 0
(-5900 10450);
DISPLAY 0.872340 (-5900 10450);
PAINT AQUA (-5900 10450);
DISPLAY INVISIBLE (-5900 10450);
FORCEADD Q_CAP..1
(-3900 9125);
FORCEPROP 1 LAST PART_NUMBER CH5223M1900
J 0
(-3850 8975);
DISPLAY 0.510638 (-3850 8975);
DISPLAY INVISIBLE (-3850 8975);
FORCEPROP 1 LAST VOLTAGE 16V
J 0
(-3850 9125);
DISPLAY 0.510638 (-3850 9125);
FORCEPROP 1 LAST VALUE 2.2UF
J 0
(-3850 9175);
DISPLAY 0.510638 (-3850 9175);
FORCEPROP 1 LAST TOLERANCE 20%
J 0
(-3850 9075);
DISPLAY 0.510638 (-3850 9075);
FORCEPROP 1 LAST PACK_TYPE C0603
J 0
(-3850 8925);
DISPLAY 0.510638 (-3850 8925);
FORCEPROP 1 LAST MATERIAL X7R
J 0
(-3850 9025);
DISPLAY 0.510638 (-3850 9025);
FORCEPROP 2 LAST ROOM NIC1_P12V_MPS_MAM_BOM3
J 0
(-3850 8900);
DISPLAY 0.510638 (-3850 8900);
FORCEPROP 1 LAST LOCATION PC2158
J 0
(-3825 9225);
DISPLAY 0.510638 (-3825 9225);
FORCEPROP 2 LAST ROOM1 NIC1_P12V_MPS_TIC_BOM4
J 0
(-3825 9325);
DISPLAY 1.021277 (-3825 9325);
DISPLAY INVISIBLE (-3825 9325);
FORCEPROP 2 LAST CDS_LIB pure_quanta
J 0
(-3900 9125);
DISPLAY INVISIBLE (-3900 9125);
FORCEPROP 1 LAST PATH I88
J 0
(-3850 9275);
DISPLAY 0.978723 (-3850 9275);
PAINT WHITE (-3850 9275);
DISPLAY INVISIBLE (-3850 9275);
FORCEPROP 0 LAST $SEC 1
J 0
(-3825 9275);
DISPLAY INVISIBLE (-3825 9275);
FORCEPROP 0 LAST CDS_SEC 1
J 0
(-3825 9275);
DISPLAY INVISIBLE (-3825 9275);
FORCEPROP 1 LASTPIN (-3900 9225) $PN 1
J 0
(-3890 9205);
DISPLAY 0.787234 (-3890 9205);
PAINT MONO (-3890 9205);
DISPLAY INVISIBLE (-3890 9205);
FORCEPROP 1 LASTPIN (-3900 9025) $PN 2
J 0
(-3890 9005);
DISPLAY 0.787234 (-3890 9005);
PAINT MONO (-3890 9005);
DISPLAY INVISIBLE (-3890 9005);
FORCEADD Q_RES..2
(-3900 9550);
FORCEPROP 1 LAST PART_NUMBER CS04993F909
J 0
(-3860 9425);
DISPLAY 0.510638 (-3860 9425);
DISPLAY INVISIBLE (-3860 9425);
FORCEPROP 1 LAST WATTAGE 1/10W
J 0
(-3860 9525);
DISPLAY 0.510638 (-3860 9525);
FORCEPROP 2 LAST ROOM NIC1_P12V_MPS_MAM_BOM3
J 0
(-3850 9725);
DISPLAY 0.510638 (-3850 9725);
FORCEPROP 1 LAST VALUE 49.9
J 0
(-3855 9625);
DISPLAY 0.510638 (-3855 9625);
FORCEPROP 1 LAST TOLERANCE 1%
J 0
(-3855 9575);
DISPLAY 0.510638 (-3855 9575);
FORCEPROP 1 LAST MATERIAL CHIP
J 0
(-3860 9475);
DISPLAY 0.510638 (-3860 9475);
FORCEPROP 1 LAST PACK_TYPE 0603LF
J 0
(-3860 9375);
DISPLAY 0.510638 (-3860 9375);
FORCEPROP 1 LAST LOCATION PR3843
J 0
(-3855 9675);
DISPLAY 0.510638 (-3855 9675);
FORCEPROP 1 LASTPIN (-3900 9650) $PN 1
J 0
(-3895 9612);
DISPLAY 0.510638 (-3895 9612);
PAINT MONO (-3895 9612);
FORCEPROP 1 LASTPIN (-3900 9450) $PN 2
J 0
(-3895 9460);
DISPLAY 0.510638 (-3895 9460);
PAINT MONO (-3895 9460);
FORCEPROP 2 LAST ROOM1 NIC1_P12V_MPS_TIC_BOM4
J 0
(-3850 9775);
DISPLAY 1.021277 (-3850 9775);
DISPLAY INVISIBLE (-3850 9775);
FORCEPROP 2 LAST CDS_LIB pure_quanta
J 0
(-3900 9550);
DISPLAY INVISIBLE (-3900 9550);
FORCEPROP 1 LAST PATH I89
J 0
(-3850 9725);
DISPLAY 0.978723 (-3850 9725);
PAINT WHITE (-3850 9725);
DISPLAY INVISIBLE (-3850 9725);
FORCEPROP 0 LAST $SEC 1
J 0
(-3850 9725);
DISPLAY 0.680851 (-3850 9725);
PAINT MONO (-3850 9725);
DISPLAY INVISIBLE (-3850 9725);
FORCEPROP 0 LAST CDS_SEC 1
J 0
(-3850 9725);
DISPLAY 1.021277 (-3850 9725);
DISPLAY INVISIBLE (-3850 9725);
FORCEADD UNIVERSAL_POWER..1
(-3900 9850);
FORCEPROP 3 LASTPIN (-3900 9800) SIG_NAME P12V_AUX\g
J 0
(-3890 9810);
DISPLAY 0.659574 (-3890 9810);
PAINT MONO (-3890 9810);
DISPLAY INVISIBLE (-3890 9810);
FORCEPROP 1 LAST HDL_POWER P12V_AUX
J 1
(-3900 9900);
DISPLAY 0.510638 (-3900 9900);
PAINT GREEN (-3900 9900);
FORCEPROP 2 LAST CDS_LIB logical_power
J 0
(-3900 9850);
DISPLAY INVISIBLE (-3900 9850);
FORCEPROP 1 LAST PATH I90
J 0
(-3850 9875);
DISPLAY 0.872340 (-3850 9875);
PAINT AQUA (-3850 9875);
DISPLAY INVISIBLE (-3850 9875);
FORCEADD Q_CAP..1
R 2
(-3550 9975);
FORCEPROP 1 LAST PART_NUMBER CH4104K1B00
J 0
(-3475 9900);
DISPLAY 0.510638 (-3475 9900);
DISPLAY INVISIBLE (-3475 9900);
FORCEPROP 2 LAST ROOM NIC1_P12V_MPS_MAM_BOM3
J 0
(-3475 10175);
DISPLAY 0.510638 (-3475 10175);
FORCEPROP 1 LAST VALUE 0.1UF
J 0
(-3475 10100);
DISPLAY 0.510638 (-3475 10100);
FORCEPROP 1 LAST VOLTAGE 25V
J 0
(-3475 10050);
DISPLAY 0.510638 (-3475 10050);
FORCEPROP 1 LAST TOLERANCE 10%
J 0
(-3475 10000);
DISPLAY 0.510638 (-3475 10000);
FORCEPROP 1 LAST MATERIAL X7R
J 0
(-3475 9950);
DISPLAY 0.510638 (-3475 9950);
FORCEPROP 1 LAST PACK_TYPE 0402
J 0
(-3475 9850);
DISPLAY 0.510638 (-3475 9850);
FORCEPROP 1 LAST LOCATION PC2160
J 0
(-3475 10125);
DISPLAY 0.510638 (-3475 10125);
FORCEPROP 1 LASTPIN (-3550 10075) $PN 1
J 2
(-3560 10055);
DISPLAY 0.510638 (-3560 10055);
PAINT MONO (-3560 10055);
FORCEPROP 1 LASTPIN (-3550 9875) $PN 2
J 2
(-3560 9855);
DISPLAY 0.510638 (-3560 9855);
PAINT MONO (-3560 9855);
FORCEPROP 2 LAST ROOM1 NIC1_P12V_MPS_TIC_BOM4
J 0
(-3475 10225);
DISPLAY 1.021277 (-3475 10225);
DISPLAY INVISIBLE (-3475 10225);
FORCEPROP 2 LAST CDS_LIB pure_quanta
J 0
(-3550 9975);
DISPLAY INVISIBLE (-3550 9975);
FORCEPROP 1 LAST PATH I91
J 2
(-3600 10125);
DISPLAY 0.978723 (-3600 10125);
PAINT WHITE (-3600 10125);
DISPLAY INVISIBLE (-3600 10125);
FORCEPROP 0 LAST $SEC 1
J 0
(-3200 10125);
DISPLAY 0.680851 (-3200 10125);
PAINT MONO (-3200 10125);
DISPLAY INVISIBLE (-3200 10125);
FORCEPROP 0 LAST CDS_SEC 1
J 0
(-3200 10125);
DISPLAY 1.021277 (-3200 10125);
DISPLAY INVISIBLE (-3200 10125);
FORCEADD GND..1
(-3550 9700);
FORCEPROP 3 LASTPIN (-3550 9750) SIG_NAME GND\g
J 0
(-3540 9760);
DISPLAY 0.659574 (-3540 9760);
PAINT MONO (-3540 9760);
DISPLAY INVISIBLE (-3540 9760);
FORCEPROP 1 LAST HDL_POWER GND
J 0
(-3550 9850);
DISPLAY 0.872340 (-3550 9850);
PAINT GREEN (-3550 9850);
DISPLAY INVISIBLE (-3550 9850);
FORCEPROP 1 LAST SIZE 1B
J 0
(-3475 9650);
DISPLAY 0.872340 (-3475 9650);
PAINT GREEN (-3475 9650);
DISPLAY INVISIBLE (-3475 9650);
FORCEPROP 2 LAST CDS_LIB logical_power
J 0
(-3550 9700);
DISPLAY INVISIBLE (-3550 9700);
FORCEPROP 1 LAST PATH I92
J 0
(-3475 9700);
DISPLAY 0.872340 (-3475 9700);
PAINT AQUA (-3475 9700);
DISPLAY INVISIBLE (-3475 9700);
FORCEADD OFFPAGE..2
(-3250 9275);
PAINT AQUA (-3250 9275);
FORCEPROP 2 LAST $XR0 157 
J 0
(-3061 9275);
DISPLAY 0.638298 (-3061 9275);
PAINT MONO (-3061 9275);
FORCEPROP 1 LAST COMMENT_BODY TRUE
J 0
(-3295 9180);
DISPLAY 0.872340 (-3295 9180);
PAINT GREEN (-3295 9180);
DISPLAY INVISIBLE (-3295 9180);
FORCEPROP 1 LAST OFFPAGE TRUE
J 0
(-2925 9150);
DISPLAY 0.872340 (-2925 9150);
PAINT AQUA (-2925 9150);
DISPLAY INVISIBLE (-2925 9150);
FORCEPROP 2 LAST CDS_LIB standard
J 0
(-3250 9275);
DISPLAY INVISIBLE (-3250 9275);
FORCEPROP 2 LAST PATH I93
J 0
(-3050 9300);
DISPLAY 1.021277 (-3050 9300);
DISPLAY INVISIBLE (-3050 9300);
FORCEADD UNIVERSAL_POWER..1
R 2
(-3550 10250);
FORCEPROP 3 LASTPIN (-3550 10200) SIG_NAME P12V_OCP_SFF\g
J 0
(-3540 10210);
DISPLAY 0.659574 (-3540 10210);
PAINT MONO (-3540 10210);
DISPLAY INVISIBLE (-3540 10210);
FORCEPROP 1 LAST HDL_POWER P12V_OCP_SFF
J 1
(-3550 10300);
DISPLAY 0.510638 (-3550 10300);
PAINT GREEN (-3550 10300);
FORCEPROP 2 LAST CDS_LIB logical_power
J 0
(-3550 10250);
DISPLAY INVISIBLE (-3550 10250);
FORCEPROP 1 LAST PATH I94
J 2
(-3600 10275);
DISPLAY 0.872340 (-3600 10275);
PAINT AQUA (-3600 10275);
DISPLAY INVISIBLE (-3600 10275);
FORCEADD OFFPAGE..2
(-2750 8625);
PAINT AQUA (-2750 8625);
FORCEPROP 2 LAST $XR0 250 
J 0
(-2561 8625);
DISPLAY 0.638298 (-2561 8625);
PAINT MONO (-2561 8625);
FORCEPROP 1 LAST COMMENT_BODY TRUE
J 0
(-2795 8530);
DISPLAY 0.872340 (-2795 8530);
PAINT GREEN (-2795 8530);
DISPLAY INVISIBLE (-2795 8530);
FORCEPROP 1 LAST OFFPAGE TRUE
J 0
(-2425 8500);
DISPLAY 0.872340 (-2425 8500);
PAINT AQUA (-2425 8500);
DISPLAY INVISIBLE (-2425 8500);
FORCEPROP 2 LAST CDS_LIB standard
J 0
(-2750 8625);
DISPLAY INVISIBLE (-2750 8625);
FORCEPROP 2 LAST PATH I95
J 0
(-2550 8650);
DISPLAY 1.021277 (-2550 8650);
DISPLAY INVISIBLE (-2550 8650);
FORCEADD OFFPAGE..2
(-2750 8450);
PAINT AQUA (-2750 8450);
FORCEPROP 2 LAST $XR0 250 
J 0
(-2561 8450);
DISPLAY 0.638298 (-2561 8450);
PAINT MONO (-2561 8450);
FORCEPROP 1 LAST COMMENT_BODY TRUE
J 0
(-2795 8355);
DISPLAY 0.872340 (-2795 8355);
PAINT GREEN (-2795 8355);
DISPLAY INVISIBLE (-2795 8355);
FORCEPROP 1 LAST OFFPAGE TRUE
J 0
(-2425 8325);
DISPLAY 0.872340 (-2425 8325);
PAINT AQUA (-2425 8325);
DISPLAY INVISIBLE (-2425 8325);
FORCEPROP 2 LAST CDS_LIB standard
J 0
(-2750 8450);
DISPLAY INVISIBLE (-2750 8450);
FORCEPROP 2 LAST PATH I96
J 0
(-2550 8475);
DISPLAY 1.021277 (-2550 8475);
DISPLAY INVISIBLE (-2550 8475);
FORCEADD QUANTA_TITLE_BLOCK_C..1
(-200 7750);
FORCEPROP 0 LAST CDS_CON_LAST_MODIFIED Fri Aug 25 14:02:22 2023
J 0
(-2085 7765);
DISPLAY INVISIBLE (-2085 7765);
FORCEPROP 2 LAST CUSTOM_TXT_CDS <XR_PAGE_TITLE>
J 0
(-8090 13000);
DISPLAY 0.638298 (-8090 13000);
PAINT PINK (-8090 13000);
DISPLAY INVISIBLE (-8090 13000);
FORCEPROP 2 LAST CUSTOM_TXT_CDS <NAME_1>
J 0
(-3375 7925);
FORCEPROP 2 LAST CUSTOM_TXT_CDS <NAME_2>
J 0
(-3375 7800);
FORCEPROP 2 LAST CUSTOM_TXT_CDS <Q_NUMBER>
J 0
(-1603 7853);
DISPLAY 1.212766 (-1603 7853);
FORCEPROP 2 LAST CUSTOM_TXT_CDS <CON_LAST_MODIFIED>
J 0
(-2085 7765);
DISPLAY 0.978723 (-2085 7765);
FORCEPROP 2 LAST CUSTOM_TXT_CDS <Q_PROJ>
J 0
(-2582 7852);
DISPLAY 1.212766 (-2582 7852);
FORCEPROP 2 LAST CUSTOM_TXT_CDS <CON_PAGE_NUM> OF <CON_TOTAL_PAGES>
J 0
(-646 7768);
DISPLAY 0.978723 (-646 7768);
FORCEPROP 2 LAST CUSTOM_TXT_CDS <Q_REV>
J 0
(-384 7853);
DISPLAY 1.212766 (-384 7853);
FORCEPROP 1 LAST Q_TITLE SFF_OCP3.0 HSC CO-LAYOUT(2/3)
J 0
(-9516 7801);
DISPLAY 2.446809 (-9516 7801);
PAINT GREEN (-9516 7801);
FORCEPROP 1 LAST Q_DEPT 
J 1
(-3963 7799);
DISPLAY 1.957447 (-3963 7799);
PAINT GREEN (-3963 7799);
FORCEPROP 2 LAST CDS_XR_PAGE_TITLE CR-157 : @S9S_MB_2U_LIB.S9S_MB_2U(SCH_1):PAGE157
J 0
(-8090 13000);
DISPLAY 0.638298 (-8090 13000);
PAINT PINK (-8090 13000);
DISPLAY INVISIBLE (-8090 13000);
FORCEPROP 2 LAST CDS_LIB pure_quanta
J 0
(-200 7750);
DISPLAY INVISIBLE (-200 7750);
FORCEPROP 1 LAST CDS_LMAN_SYM_OUTLINE -9475,6775,100,-125
J 0
(-200 7750);
DISPLAY 0.468085 (-200 7750);
PAINT GREEN (-200 7750);
DISPLAY INVISIBLE (-200 7750);
FORCEPROP 1 LAST COMMENT_BODY TRUE
J 0
(-188 7737);
DISPLAY 0.978723 (-188 7737);
PAINT GREEN (-188 7737);
DISPLAY INVISIBLE (-188 7737);
FORCEPROP 2 LAST PAGE_BORDER TRUE
J 0
(-8090 13000);
DISPLAY 0.638298 (-8090 13000);
PAINT PINK (-8090 13000);
DISPLAY INVISIBLE (-8090 13000);
FORCEADD DNS..2
(-3950 8625);
PAINT RED (-3950 8625);
FORCEPROP 2 LAST CDS_LIB mstr_misc
J 0
(-3950 8625);
DISPLAY INVISIBLE (-3950 8625);
FORCEPROP 1 LAST COMMENT_BODY TRUE
R 1
J 0
(-3875 8400);
DISPLAY 0.872340 (-3875 8400);
PAINT GREEN (-3875 8400);
DISPLAY INVISIBLE (-3875 8400);
FORCEADD DNS..2
(-5400 9625);
PAINT RED (-5400 9625);
FORCEPROP 2 LAST CDS_LIB mstr_misc
J 0
(-5400 9625);
DISPLAY INVISIBLE (-5400 9625);
FORCEPROP 1 LAST COMMENT_BODY TRUE
R 1
J 0
(-5325 9400);
DISPLAY 0.872340 (-5325 9400);
PAINT GREEN (-5325 9400);
DISPLAY INVISIBLE (-5325 9400);
FORCEADD DNS..2
(-4800 9625);
PAINT RED (-4800 9625);
FORCEPROP 2 LAST CDS_LIB mstr_misc
J 0
(-4800 9625);
DISPLAY INVISIBLE (-4800 9625);
FORCEPROP 1 LAST COMMENT_BODY TRUE
R 1
J 0
(-4725 9400);
DISPLAY 0.872340 (-4725 9400);
PAINT GREEN (-4725 9400);
DISPLAY INVISIBLE (-4725 9400);
FORCEADD CAD_NOTE..1
(-3475 8375);
FORCEPROP 0 LAST S1 R3871/R3872 CO-LAYOUT
J 0
(-3600 8250);
DISPLAY 0.510638 (-3600 8250);
PAINT WHITE (-3600 8250);
FORCEPROP 1 LAST COMMENT_BODY TRUE
J 0
(-3450 8475);
DISPLAY 0.978723 (-3450 8475);
DISPLAY INVISIBLE (-3450 8475);
FORCEPROP 2 LAST CDS_LIB logical_power
J 0
(-3475 8375);
DISPLAY INVISIBLE (-3475 8375);
FORCEADD DNS..2
(-4275 12275);
PAINT RED (-4275 12275);
FORCEPROP 1 LAST COMMENT_BODY TRUE
R 1
J 0
(-4200 12050);
DISPLAY 0.872340 (-4200 12050);
PAINT GREEN (-4200 12050);
DISPLAY INVISIBLE (-4200 12050);
FORCEPROP 2 LAST CDS_LIB mstr_misc
J 0
(-4275 12275);
DISPLAY INVISIBLE (-4275 12275);
FORCEADD DNS..2
(-3825 12275);
PAINT RED (-3825 12275);
FORCEPROP 2 LAST CDS_LIB mstr_misc
J 0
(-3825 12275);
DISPLAY INVISIBLE (-3825 12275);
FORCEPROP 1 LAST COMMENT_BODY TRUE
R 1
J 0
(-3750 12050);
DISPLAY 0.872340 (-3750 12050);
PAINT GREEN (-3750 12050);
DISPLAY INVISIBLE (-3750 12050);
FORCEADD DNS..2
(-3525 12225);
PAINT RED (-3525 12225);
FORCEPROP 2 LAST CDS_LIB mstr_misc
J 0
(-3525 12225);
DISPLAY INVISIBLE (-3525 12225);
FORCEPROP 1 LAST COMMENT_BODY TRUE
R 1
J 0
(-3450 12000);
DISPLAY 0.872340 (-3450 12000);
PAINT GREEN (-3450 12000);
DISPLAY INVISIBLE (-3450 12000);
FORCEADD DNS..2
(-3750 12600);
PAINT RED (-3750 12600);
FORCEPROP 2 LAST CDS_LIB mstr_misc
J 0
(-3750 12600);
DISPLAY INVISIBLE (-3750 12600);
FORCEPROP 1 LAST COMMENT_BODY TRUE
R 1
J 0
(-3675 12375);
DISPLAY 0.872340 (-3675 12375);
PAINT GREEN (-3675 12375);
DISPLAY INVISIBLE (-3675 12375);
FORCEADD DNS..2
(-3575 12850);
PAINT RED (-3575 12850);
FORCEPROP 2 LAST CDS_LIB mstr_misc
J 0
(-3575 12850);
DISPLAY INVISIBLE (-3575 12850);
FORCEPROP 1 LAST COMMENT_BODY TRUE
R 1
J 0
(-3500 12625);
DISPLAY 0.872340 (-3500 12625);
PAINT GREEN (-3500 12625);
DISPLAY INVISIBLE (-3500 12625);
FORCEADD DNS..2
(-2975 12200);
PAINT RED (-2975 12200);
FORCEPROP 2 LAST CDS_LIB mstr_misc
J 0
(-2975 12200);
DISPLAY INVISIBLE (-2975 12200);
FORCEPROP 1 LAST COMMENT_BODY TRUE
R 1
J 0
(-2900 11975);
DISPLAY 0.872340 (-2900 11975);
PAINT GREEN (-2900 11975);
DISPLAY INVISIBLE (-2900 11975);
FORCEADD DNS..2
(-2350 12675);
PAINT RED (-2350 12675);
FORCEPROP 2 LAST CDS_LIB mstr_misc
J 0
(-2350 12675);
DISPLAY INVISIBLE (-2350 12675);
FORCEPROP 1 LAST COMMENT_BODY TRUE
R 1
J 0
(-2275 12450);
DISPLAY 0.872340 (-2275 12450);
PAINT GREEN (-2275 12450);
DISPLAY INVISIBLE (-2275 12450);
FORCEADD DNS..2
(-1475 12125);
PAINT RED (-1475 12125);
FORCEPROP 2 LAST CDS_LIB mstr_misc
J 0
(-1475 12125);
DISPLAY INVISIBLE (-1475 12125);
FORCEPROP 1 LAST COMMENT_BODY TRUE
R 1
J 0
(-1400 11900);
DISPLAY 0.872340 (-1400 11900);
PAINT GREEN (-1400 11900);
DISPLAY INVISIBLE (-1400 11900);
FORCEADD DNS..2
(-875 12350);
PAINT RED (-875 12350);
FORCEPROP 1 LAST COMMENT_BODY TRUE
R 1
J 0
(-800 12125);
DISPLAY 0.872340 (-800 12125);
PAINT GREEN (-800 12125);
DISPLAY INVISIBLE (-800 12125);
FORCEPROP 2 LAST CDS_LIB mstr_misc
J 0
(-875 12350);
DISPLAY INVISIBLE (-875 12350);
WIRE 16 -1 (-7300 10350)(-7300 10250);
WIRE 16 -1 (-5325 9150)(-4800 9150);
WIRE 16 -1 (-5950 10375)(-5950 10325);
WIRE 16 -1 (-3900 9800)(-3900 9750);
WIRE 16 -1 (-3550 10150)(-3550 10200);
WIRE 16 -1 (-4825 10150)(-3550 10150);
WIRE 16 -1 (-3550 10075)(-3550 10150);
WIRE 16 -1 (-3550 13075)(-3550 13150);
WIRE 16 -1 (-3550 13075)(-2950 13075);
WIRE 16 -1 (-3550 12975)(-3550 13075);
WIRE 16 -1 (-875 12700)(-875 12975);
WIRE 16 -1 (-875 12700)(-875 12475);
WIRE 16 -1 (-1925 12700)(-875 12700);
WIRE 16 -1 (-8050 8900)(-8050 9100);
WIRE 16 -1 (-7625 8825)(-7625 8975);
WIRE 16 -1 (-7225 8800)(-7225 8875);
WIRE 16 -1 (-7150 9450)(-7625 9450);
WIRE 16 -1 (-7150 9550)(-7150 9450);
WIRE 16 -1 (-7150 9450)(-6825 9450);
WIRE 16 -1 (-7300 9875)(-7300 9950);
WIRE 16 -1 (-6884 8966)(-6884 9050);
WIRE 16 -1 (-5350 8495)(-5350 8425);
WIRE 16 -1 (-5800 8495)(-5350 8495);
WIRE 16 -1 (-5350 8495)(-5350 8675);
WIRE 16 -1 (-4225 8875)(-4225 8850);
WIRE 16 -1 (-4425 8875)(-4225 8875);
WIRE 16 -1 (-4225 8875)(-3900 8875);
WIRE 16 -1 (-3550 9750)(-3550 9875);
WIRE 16 -1 (-4275 12075)(-4275 11975);
WIRE 16 -1 (-3825 12075)(-4275 12075);
WIRE 16 -1 (-4275 12200)(-4275 12075);
WIRE 16 -1 (-3525 12150)(-3525 11975);
WIRE 16 -1 (-3550 12775)(-3550 12700);
WIRE 16 -1 (-2975 12125)(-2975 11975);
WIRE 16 -1 (-1475 11975)(-1475 11850);
WIRE 16 -1 (-1750 11975)(-1475 11975);
WIRE 16 -1 (-1475 12050)(-1475 11975);
WIRE 16 -1 (-875 12075)(-875 12275);
WIRE 16 -1 (-6025 9500)(-5718 9500);
WIRE 16 -1 (-6025 9550)(-5718 9550);
WIRE 16 -1 (-5718 9550)(-5718 9500);
WIRE 16 -1 (-6025 9600)(-5718 9600);
WIRE 16 -1 (-5718 9550)(-5718 9600);
WIRE 16 -1 (-5718 9650)(-6025 9650);
WIRE 16 -1 (-5718 9600)(-5718 9650);
WIRE 16 -1 (-6025 9700)(-5718 9700);
WIRE 16 -1 (-5718 9650)(-5718 9700);
WIRE 16 -1 (-5718 9700)(-5718 9750);
WIRE 16 -1 (-6025 9750)(-5718 9750);
WIRE 16 -1 (-6025 9800)(-5718 9800);
WIRE 16 -1 (-5718 9750)(-5718 9800);
WIRE 16 -1 (-6025 9850)(-5718 9850);
WIRE 16 -1 (-5718 9800)(-5718 9850);
WIRE 16 -1 (-5718 9850)(-5425 9850);
WIRE 16 -1 (-5425 9725)(-5425 9850);
WIRE 16 -1 (-5425 9850)(-4825 9850);
WIRE 16 -1 (-4825 9850)(-4825 9725);
WIRE 16 -1 (-4825 9850)(-4825 10150);
WIRE 16 -1 (-6025 10000)(-5950 10000);
WIRE 16 -1 (-5200 10000)(-5950 10000);
FORCEPROP 2 LAST SIG_NAME HP_LVC3_OCP_V3_1_P12V_PWRGD
J 0
(-5910 10010);
DISPLAY 0.510638 (-5910 10010);
WIRE 16 -1 (-5950 10125)(-5950 10000);
WIRE 16 -1 (-4450 8450)(-4100 8450);
WIRE 16 -1 (-4450 8625)(-4450 8450);
WIRE 16 -1 (-4100 8625)(-4450 8625);
WIRE 16 -1 (-4725 8625)(-4450 8625);
WIRE 16 -1 (-4725 9050)(-4725 8625);
WIRE 16 -1 (-5350 8875)(-5350 9050);
WIRE 16 -1 (-5350 9050)(-4725 9050);
WIRE 16 -1 (-5800 8875)(-5800 9050);
FORCEPROP 2 LAST SIG_NAME P12V_OCP_IMON_1
J 0
(-5935 9060);
DISPLAY 0.510638 (-5935 9060);
WIRE 16 -1 (-5800 9050)(-5350 9050);
WIRE 16 -1 (-6025 9050)(-5800 9050);
WIRE 16 -1 (-3900 8875)(-3900 9025);
WIRE 16 -1 (-4425 9025)(-4425 8875);
WIRE 16 -1 (-4425 9450)(-4425 9300);
WIRE 16 -1 (-4425 9300)(-4425 9225);
WIRE 16 -1 (-4825 9525)(-4825 9300);
WIRE 16 -1 (-4425 9300)(-4825 9300);
WIRE 16 -1 (-6025 9300)(-4825 9300);
FORCEPROP 2 LAST SIG_NAME P12V_OCP_OV_FB_1
J 0
(-5935 9310);
DISPLAY 0.510638 (-5935 9310);
WIRE 16 -1 (-3900 8450)(-2800 8450);
FORCEPROP 2 LAST SIG_NAME P12V_OCP_SFF_ISENSE_MPS_TIC
J 0
(-3660 8460);
DISPLAY 0.510638 (-3660 8460);
WIRE 16 2175 (-4400 8375)(-3675 8375);
WIRE 16 2175 (-3675 8675)(-3675 8375);
WIRE 16 2175 (-4400 8675)(-4400 8375);
WIRE 16 2175 (-4400 8675)(-3675 8675);
WIRE 16 -1 (-3900 8625)(-2800 8625);
FORCEPROP 2 LAST SIG_NAME P12V_OCP_SFF_ISENSE_MPS_MAM
J 0
(-3660 8635);
DISPLAY 0.510638 (-3660 8635);
WIRE 16 3135 (-6600 11225)(-5350 11225);
WIRE 16 3135 (-5350 10575)(-5350 11225);
WIRE 16 3135 (-6600 10575)(-6600 11225);
WIRE 16 3135 (-6600 10575)(-5350 10575);
WIRE 16 3135 (-6575 11075)(-5375 11075);
WIRE 16 3135 (-6575 10975)(-5375 10975);
WIRE 16 3135 (-6575 10775)(-5375 10775);
WIRE 16 -1 (-3900 9450)(-3900 9275);
WIRE 16 -1 (-3900 9275)(-3900 9225);
WIRE 16 -1 (-3300 9275)(-3900 9275);
FORCEPROP 2 LAST SIG_NAME P12V_OCP_AVIN_PD_1
J 0
(-3785 9285);
DISPLAY 0.510638 (-3785 9285);
WIRE 16 -1 (-3900 9750)(-3900 9650);
WIRE 16 -1 (-4425 9750)(-3900 9750);
WIRE 16 -1 (-4425 9650)(-4425 9750);
WIRE 16 3135 (-5800 11200)(-5800 10600);
WIRE 16 -1 (-5425 9525)(-5425 9400);
WIRE 16 -1 (-5425 9400)(-5275 9400);
WIRE 16 -1 (-6025 9400)(-5425 9400);
FORCEPROP 2 LAST SIG_NAME P12V_OCP_AVIN_PD_1
J 0
(-5935 9410);
DISPLAY 0.510638 (-5935 9410);
WIRE 16 -1 (-5800 8675)(-5800 8495);
WIRE 16 -1 (-5525 9150)(-6025 9150);
FORCEPROP 2 LAST SIG_NAME P12V_OCP_FLTB_1
J 0
(-5935 9160);
DISPLAY 0.510638 (-5935 9160);
WIRE 16 3135 (-6575 10875)(-5375 10875);
WIRE 16 3135 (-6575 10675)(-5375 10675);
WIRE 16 3135 (-6225 11200)(-6225 10600);
WIRE 16 -1 (-7300 10250)(-7300 10150);
WIRE 16 -1 (-6905 10250)(-7300 10250);
WIRE 16 -1 (-6905 10000)(-6825 10000);
WIRE 16 -1 (-6905 10250)(-6905 10000);
WIRE 16 -1 (-6825 9950)(-6905 9950);
WIRE 16 -1 (-6905 9950)(-6905 10000);
WIRE 16 -1 (-6905 9900)(-6905 9950);
WIRE 16 -1 (-6825 9900)(-6905 9900);
WIRE 16 -1 (-6825 9850)(-6905 9850);
WIRE 16 -1 (-6905 9850)(-6905 9900);
WIRE 16 -1 (-6905 9800)(-6905 9850);
WIRE 16 -1 (-6825 9800)(-6905 9800);
WIRE 16 -1 (-6884 9050)(-6825 9050);
WIRE 16 -1 (-7650 9650)(-6825 9650);
FORCEPROP 2 LAST SIG_NAME P12V_OCP_EN_1_R2
J 0
(-7335 9660);
DISPLAY 0.510638 (-7335 9660);
WIRE 16 -1 (-6825 9550)(-7150 9550);
WIRE 16 -1 (-8050 9350)(-8050 9300);
WIRE 16 -1 (-6825 9350)(-8050 9350);
FORCEPROP 2 LAST SIG_NAME P12V_OCP_TIMER_1
J 0
(-7310 9360);
DISPLAY 0.510638 (-7310 9360);
WIRE 16 -1 (-7625 9250)(-7625 9175);
WIRE 16 -1 (-6825 9250)(-7625 9250);
FORCEPROP 2 LAST SIG_NAME P12V_OCP_ISET_1
J 0
(-7285 9260);
DISPLAY 0.510638 (-7285 9260);
WIRE 16 -1 (-7225 9150)(-7225 9075);
WIRE 16 -1 (-6825 9150)(-7225 9150);
FORCEPROP 2 LAST SIG_NAME P12V_OCP_SS_1
J 0
(-7235 9160);
DISPLAY 0.510638 (-7235 9160);
WIRE 16 -1 (-7850 9650)(-8525 9650);
FORCEPROP 2 LAST SIG_NAME HP_LVC3_OCP_V3_1_EN
J 0
(-8485 9660);
DISPLAY 0.510638 (-8485 9660);
WIRE 16 2175 (-9350 13000)(-7647 13000);
WIRE 16 2175 (-7647 13900)(-7647 13000);
WIRE 16 2175 (-9350 13900)(-9350 13000);
WIRE 16 2175 (-9350 13900)(-7647 13900);
WIRE 16 -1 (-2975 12400)(-2725 12400);
WIRE 16 -1 (-2975 12325)(-2975 12400);
FORCEPROP 2 LAST SIG_NAME P3V3_OCP_DVDT_1
J 0
(-3260 12410);
DISPLAY 0.574468 (-3260 12410);
WIRE 16 -1 (-1475 12250)(-1475 12500);
WIRE 16 -1 (-1925 12500)(-1475 12500);
FORCEPROP 2 LAST SIG_NAME P3V3_OCP_GATE_1
J 0
(-1835 12510);
DISPLAY 0.574468 (-1835 12510);
WIRE 16 -1 (-2950 12700)(-2725 12700);
WIRE 16 -1 (-2950 13075)(-2950 12700);
WIRE 16 -1 (-3525 12350)(-3525 12450);
WIRE 16 -1 (-3525 12450)(-2725 12450);
FORCEPROP 2 LAST SIG_NAME P3V3_OCP_ILIMIT_1
J 0
(-3310 12460);
DISPLAY 0.574468 (-3310 12460);
WIRE 16 -1 (-3825 12400)(-3825 12500);
WIRE 16 -1 (-2725 12500)(-3825 12500);
FORCEPROP 2 LAST SIG_NAME P3V3_OCP_MODE_1
J 0
(-3260 12510);
DISPLAY 0.574468 (-3260 12510);
WIRE 16 -1 (-4275 12500)(-3825 12500);
WIRE 16 -1 (-4275 12400)(-4275 12500);
WIRE 16 -1 (-1750 12400)(-1750 11975);
WIRE 16 -1 (-1925 12400)(-1750 12400);
WIRE 16 -1 (-3825 12200)(-3825 12075);
WIRE 16 -1 (-3875 12600)(-4650 12600);
FORCEPROP 2 LAST SIG_NAME HP_LVC3_OCP_V3_1_EN
J 0
(-4635 12610);
DISPLAY 0.638298 (-4635 12610);
WIRE 16 -1 (-2725 12600)(-3675 12600);
FORCEPROP 2 LAST SIG_NAME P3V3_OCP_EN_1_R2
J 0
(-3310 12610);
DISPLAY 0.574468 (-3310 12610);
DOT 1 (-5950 10000);
DOT 1 (-5350 9050);
DOT 1 (-4275 12075);
DOT 1 (-3550 13075);
DOT 1 (-1475 11975);
DOT 1 (-875 12700);
DOT 1 (-3825 12500);
DOT 1 (-7150 9450);
DOT 1 (-6905 9850);
DOT 1 (-6905 9900);
DOT 1 (-6905 9950);
DOT 1 (-6905 10000);
DOT 1 (-7300 10250);
DOT 1 (-5800 9050);
DOT 1 (-5350 8495);
DOT 1 (-5718 9550);
DOT 1 (-5718 9600);
DOT 1 (-5718 9650);
DOT 1 (-5718 9700);
DOT 1 (-5718 9750);
DOT 1 (-5718 9800);
DOT 1 (-5718 9850);
DOT 1 (-5425 9400);
DOT 1 (-5425 9850);
DOT 1 (-4450 8625);
DOT 1 (-4225 8875);
DOT 1 (-4825 9300);
DOT 1 (-4825 9850);
DOT 1 (-4425 9300);
DOT 1 (-3900 9275);
DOT 1 (-3900 9750);
DOT 1 (-3550 10150);
FORCENOTE
=1.6A
(-3825 11725) 0;
DISPLAY LEFT (-3825 11725);
DISPLAY 1.021277 (-3825 11725);
PAINT WHITE (-3825 11725);
FORCENOTE
START UP TIME:4.7MS
(-2775 11675) 0;
DISPLAY LEFT (-2775 11675);
DISPLAY 1.021277 (-2775 11675);
PAINT WHITE (-2775 11675);
FORCENOTE
P12V_OCP_V3
(-9275 13275) 0;
DISPLAY LEFT (-9275 13275);
DISPLAY 1.021277 (-9275 13275);
FORCENOTE
IMAX=6.6A
(-9275 13200) 0;
DISPLAY LEFT (-9275 13200);
DISPLAY 1.021277 (-9275 13200);
FORCENOTE
P3V3_OCP_V3
(-9275 13675) 0;
DISPLAY LEFT (-9275 13675);
DISPLAY 0.936170 (-9275 13675);
FORCENOTE
IMAX=1.1A
(-9275 13600) 0;
DISPLAY LEFT (-9275 13600);
DISPLAY 0.936170 (-9275 13600);
FORCENOTE
DESIGN SPECIFICATION
(-9291 13794) 0;
DISPLAY LEFT (-9291 13794);
DISPLAY 1.170213 (-9291 13794);
FORCENOTE
OCP=IMAX*1.3=1.43A
(-9275 13525) 0;
DISPLAY LEFT (-9275 13525);
DISPLAY 0.936170 (-9275 13525);
FORCENOTE
OCP=IMAX*1.3=8.58A
(-9275 13125) 0;
DISPLAY LEFT (-9275 13125);
DISPLAY 1.021277 (-9275 13125);
FORCENOTE
20211108 MODIFY FOR GT
(-7025 13775) 0;
DISPLAY LEFT (-7025 13775);
DISPLAY 2.510638 (-7025 13775);
PAINT PINK (-7025 13775);
FORCENOTE
CURRENT LIMIT
(-3825 11791) 0;
DISPLAY LEFT (-3825 11791);
DISPLAY 1.021277 (-3825 11791);
PAINT WHITE (-3825 11791);
FORCENOTE
ENABLE:
(-9125 9416) 0;
DISPLAY LEFT (-9125 9416);
DISPLAY 1.021277 (-9125 9416);
PAINT WHITE (-9125 9416);
FORCENOTE
VTH>1.391V(HIGH)
(-9125 9350) 0;
DISPLAY LEFT (-9125 9350);
DISPLAY 1.021277 (-9125 9350);
PAINT WHITE (-9125 9350);
FORCENOTE
TDELAY: 6.29MS
(-8575 8600) 0;
DISPLAY LEFT (-8575 8600);
DISPLAY 1.021277 (-8575 8600);
PAINT WHITE (-8575 8600);
FORCENOTE
TFAULT: 1.27MS
(-8575 8675) 0;
DISPLAY LEFT (-8575 8675);
DISPLAY 1.021277 (-8575 8675);
PAINT WHITE (-8575 8675);
FORCENOTE
START UP TIME:8.62MS
(-7625 8600) 0;
DISPLAY LEFT (-7625 8600);
DISPLAY 1.021277 (-7625 8600);
PAINT WHITE (-7625 8600);
FORCENOTE
PR3840
(-6525 11000) 0;
DISPLAY LEFT (-6525 11000);
DISPLAY 1.021277 (-6525 11000);
FORCENOTE
PR3838
(-6525 10900) 0;
DISPLAY LEFT (-6525 10900);
DISPLAY 1.021277 (-6525 10900);
FORCENOTE
PR3841
(-6525 10800) 0;
DISPLAY LEFT (-6525 10800);
DISPLAY 1.021277 (-6525 10800);
FORCENOTE
PR3843
(-6525 10700) 0;
DISPLAY LEFT (-6525 10700);
DISPLAY 1.021277 (-6525 10700);
FORCENOTE
PC2158
(-6525 10600) 0;
DISPLAY LEFT (-6525 10600);
DISPLAY 1.021277 (-6525 10600);
FORCENOTE
VIMON(MAX)= 1.582V @ IOUT=9.09A
(-7150 8275) 0;
DISPLAY LEFT (-7150 8275);
DISPLAY 1.021277 (-7150 8275);
PAINT WHITE (-7150 8275);
FORCENOTE
MP5022C
(-6200 11100) 0;
DISPLAY LEFT (-6200 11100);
DISPLAY 1.021277 (-6200 11100);
FORCENOTE
POP
(-6175 10700) 0;
DISPLAY LEFT (-6175 10700);
DISPLAY 1.021277 (-6175 10700);
FORCENOTE
POP
(-6175 10600) 0;
DISPLAY LEFT (-6175 10600);
DISPLAY 1.021277 (-6175 10600);
FORCENOTE
MP5025C/
(-6200 11150) 0;
DISPLAY LEFT (-6200 11150);
DISPLAY 1.021277 (-6200 11150);
FORCENOTE
MP5022A
(-5750 11100) 0;
DISPLAY LEFT (-5750 11100);
DISPLAY 1.021277 (-5750 11100);
FORCENOTE
DE-POP
(-5750 10700) 0;
DISPLAY LEFT (-5750 10700);
DISPLAY 1.021277 (-5750 10700);
FORCENOTE
DE-POP
(-5750 10800) 0;
DISPLAY LEFT (-5750 10800);
DISPLAY 1.021277 (-5750 10800);
FORCENOTE
DE-POP
(-5750 10600) 0;
DISPLAY LEFT (-5750 10600);
DISPLAY 1.021277 (-5750 10600);
FORCENOTE
POP
(-5700 10900) 0;
DISPLAY LEFT (-5700 10900);
DISPLAY 1.021277 (-5700 10900);
FORCENOTE
MP5025A/
(-5750 11150) 0;
DISPLAY LEFT (-5750 11150);
DISPLAY 1.021277 (-5750 11150);
FORCENOTE
POP
(-5700 11000) 0;
DISPLAY LEFT (-5700 11000);
DISPLAY 1.021277 (-5700 11000);
FORCENOTE
POP
(-6175 10800) 0;
DISPLAY LEFT (-6175 10800);
DISPLAY 1.021277 (-6175 10800);
FORCENOTE
DE-POP
(-6175 10900) 0;
DISPLAY LEFT (-6175 10900);
DISPLAY 1.021277 (-6175 10900);
FORCENOTE
DE-POP
(-6175 11000) 0;
DISPLAY LEFT (-6175 11000);
DISPLAY 1.021277 (-6175 11000);
FORCENOTE
PU204 OPTIONAL BOM
(-6575 11250) 0;
DISPLAY LEFT (-6575 11250);
DISPLAY 1.021277 (-6575 11250);
QUIT
